FILE_TYPE = MACRO_DRAWING;
SET COLOR_WIRE YELLOW;
SET COLOR_PROP ORANGE;
SET COLOR_DOT WHITE;
SET COLOR_ARC YELLOW;
SET COLOR_BODY GREEN;
SET COLOR_NOTE PURPLE;
SET PROP_DISPLAY VALUE;
SET PAGE_NUMBER P57;
FORCEADD OFFPAGE..2
R 2
(-2225 -75);
FORCEPROP 2 LAST $XR1 111 
J 0
(-2600 -75);
DISPLAY 0.638298 (-2600 -75);
PAINT MONO (-2600 -75);
FORCEPROP 2 LAST $XR0 110 
J 0
(-2480 -75);
DISPLAY 0.638298 (-2480 -75);
PAINT MONO (-2480 -75);
FORCEPROP 2 LAST CDS_LIB standard
J 0
(-2225 -75);
PAINT MONO (-2225 -75);
DISPLAY INVISIBLE (-2225 -75);
FORCEPROP 1 LAST OFFPAGE TRUE
J 2
(-2550 -200);
DISPLAY 0.872340 (-2550 -200);
DISPLAY INVISIBLE (-2550 -200);
FORCEPROP 1 LAST COMMENT_BODY TRUE
J 2
(-2180 -170);
DISPLAY 0.872340 (-2180 -170);
PAINT GREEN (-2180 -170);
DISPLAY INVISIBLE (-2180 -170);
FORCEPROP 2 LAST PATH I1
J 0
(-2175 0);
DISPLAY 1.021277 (-2175 0);
DISPLAY INVISIBLE (-2175 0);
FORCEADD TAP..1
R 2
(-1200 150);
FORCEPROP 3 LASTPIN (-1150 150) SIG_NAME M_G_CPU1_SB_CB<1>
J 0
(-1140 160);
DISPLAY 0.659574 (-1140 160);
PAINT MONO (-1140 160);
DISPLAY INVISIBLE (-1140 160);
FORCEPROP 1 LASTPIN (-1150 150) BN 1
J 2
(-1138 158);
DISPLAY 0.680851 (-1138 158);
PAINT GREEN (-1138 158);
FORCEPROP 2 LAST CDS_LIB standard
J 0
(-1200 150);
DISPLAY INVISIBLE (-1200 150);
FORCEPROP 1 LAST BODY_TYPE PLUMBING
J 2
(-1200 200);
DISPLAY 0.872340 (-1200 200);
PAINT GREEN (-1200 200);
DISPLAY INVISIBLE (-1200 200);
FORCEPROP 1 LAST HDL_TAP TRUE
J 2
(-1525 25);
DISPLAY 0.872340 (-1525 25);
DISPLAY INVISIBLE (-1525 25);
FORCEPROP 1 LAST PATH I10
J 2
(-1198 150);
DISPLAY 0.872340 (-1198 150);
PAINT GREEN (-1198 150);
DISPLAY INVISIBLE (-1198 150);
FORCEADD TAP..1
(2225 750);
FORCEPROP 3 LASTPIN (2175 750) SIG_NAME M_G_CPU1_SA_CS_N<3>
J 0
(2185 760);
DISPLAY 0.659574 (2185 760);
PAINT MONO (2185 760);
DISPLAY INVISIBLE (2185 760);
FORCEPROP 1 LASTPIN (2175 750) BN 3
J 0
(2163 758);
DISPLAY 0.680851 (2163 758);
PAINT GREEN (2163 758);
FORCEPROP 2 LAST CDS_LIB standard
J 0
(2225 750);
DISPLAY INVISIBLE (2225 750);
FORCEPROP 1 LAST BODY_TYPE PLUMBING
J 0
(2225 800);
DISPLAY 0.872340 (2225 800);
PAINT GREEN (2225 800);
DISPLAY INVISIBLE (2225 800);
FORCEPROP 1 LAST HDL_TAP TRUE
J 0
(2550 625);
DISPLAY 0.872340 (2550 625);
DISPLAY INVISIBLE (2550 625);
FORCEPROP 1 LAST PATH I100
J 0
(2223 750);
DISPLAY 0.872340 (2223 750);
PAINT GREEN (2223 750);
DISPLAY INVISIBLE (2223 750);
FORCEADD TAP..1
(2225 650);
FORCEPROP 3 LASTPIN (2175 650) SIG_NAME M_G_CPU1_SA_CS_N<1>
J 0
(2185 660);
DISPLAY 0.659574 (2185 660);
PAINT MONO (2185 660);
DISPLAY INVISIBLE (2185 660);
FORCEPROP 1 LASTPIN (2175 650) BN 1
J 0
(2163 658);
DISPLAY 0.680851 (2163 658);
PAINT GREEN (2163 658);
FORCEPROP 2 LAST CDS_LIB standard
J 0
(2225 650);
DISPLAY INVISIBLE (2225 650);
FORCEPROP 1 LAST BODY_TYPE PLUMBING
J 0
(2225 700);
DISPLAY 0.872340 (2225 700);
PAINT GREEN (2225 700);
DISPLAY INVISIBLE (2225 700);
FORCEPROP 1 LAST HDL_TAP TRUE
J 0
(2550 525);
DISPLAY 0.872340 (2550 525);
DISPLAY INVISIBLE (2550 525);
FORCEPROP 1 LAST PATH I101
J 0
(2223 650);
DISPLAY 0.872340 (2223 650);
PAINT GREEN (2223 650);
DISPLAY INVISIBLE (2223 650);
FORCEADD TAP..1
(2225 950);
FORCEPROP 3 LASTPIN (2175 950) SIG_NAME M_G_CPU1_SB_CA<0>
J 0
(2185 960);
DISPLAY 0.659574 (2185 960);
PAINT MONO (2185 960);
DISPLAY INVISIBLE (2185 960);
FORCEPROP 1 LASTPIN (2175 950) BN 0
J 0
(2163 958);
DISPLAY 0.680851 (2163 958);
PAINT GREEN (2163 958);
FORCEPROP 2 LAST CDS_LIB standard
J 0
(2225 950);
DISPLAY INVISIBLE (2225 950);
FORCEPROP 1 LAST BODY_TYPE PLUMBING
J 0
(2225 1000);
DISPLAY 0.872340 (2225 1000);
PAINT GREEN (2225 1000);
DISPLAY INVISIBLE (2225 1000);
FORCEPROP 1 LAST HDL_TAP TRUE
J 0
(2550 825);
DISPLAY 0.872340 (2550 825);
DISPLAY INVISIBLE (2550 825);
FORCEPROP 1 LAST PATH I102
J 0
(2223 950);
DISPLAY 0.872340 (2223 950);
PAINT GREEN (2223 950);
DISPLAY INVISIBLE (2223 950);
FORCEADD TAP..1
(2225 1000);
FORCEPROP 3 LASTPIN (2175 1000) SIG_NAME M_G_CPU1_SB_CA<1>
J 0
(2185 1010);
DISPLAY 0.659574 (2185 1010);
PAINT MONO (2185 1010);
DISPLAY INVISIBLE (2185 1010);
FORCEPROP 1 LASTPIN (2175 1000) BN 1
J 0
(2163 1008);
DISPLAY 0.680851 (2163 1008);
PAINT GREEN (2163 1008);
FORCEPROP 2 LAST CDS_LIB standard
J 0
(2225 1000);
DISPLAY INVISIBLE (2225 1000);
FORCEPROP 1 LAST BODY_TYPE PLUMBING
J 0
(2225 1050);
DISPLAY 0.872340 (2225 1050);
PAINT GREEN (2225 1050);
DISPLAY INVISIBLE (2225 1050);
FORCEPROP 1 LAST HDL_TAP TRUE
J 0
(2550 875);
DISPLAY 0.872340 (2550 875);
DISPLAY INVISIBLE (2550 875);
FORCEPROP 1 LAST PATH I103
J 0
(2223 1000);
DISPLAY 0.872340 (2223 1000);
PAINT GREEN (2223 1000);
DISPLAY INVISIBLE (2223 1000);
FORCEADD TAP..1
(2225 1050);
FORCEPROP 3 LASTPIN (2175 1050) SIG_NAME M_G_CPU1_SB_CA<2>
J 0
(2185 1060);
DISPLAY 0.659574 (2185 1060);
PAINT MONO (2185 1060);
DISPLAY INVISIBLE (2185 1060);
FORCEPROP 1 LASTPIN (2175 1050) BN 2
J 0
(2163 1058);
DISPLAY 0.680851 (2163 1058);
PAINT GREEN (2163 1058);
FORCEPROP 2 LAST CDS_LIB standard
J 0
(2225 1050);
DISPLAY INVISIBLE (2225 1050);
FORCEPROP 1 LAST BODY_TYPE PLUMBING
J 0
(2225 1100);
DISPLAY 0.872340 (2225 1100);
PAINT GREEN (2225 1100);
DISPLAY INVISIBLE (2225 1100);
FORCEPROP 1 LAST HDL_TAP TRUE
J 0
(2550 925);
DISPLAY 0.872340 (2550 925);
DISPLAY INVISIBLE (2550 925);
FORCEPROP 1 LAST PATH I104
J 0
(2223 1050);
DISPLAY 0.872340 (2223 1050);
PAINT GREEN (2223 1050);
DISPLAY INVISIBLE (2223 1050);
FORCEADD TAP..1
(2225 1100);
FORCEPROP 3 LASTPIN (2175 1100) SIG_NAME M_G_CPU1_SB_CA<3>
J 0
(2185 1110);
DISPLAY 0.659574 (2185 1110);
PAINT MONO (2185 1110);
DISPLAY INVISIBLE (2185 1110);
FORCEPROP 1 LASTPIN (2175 1100) BN 3
J 0
(2163 1108);
DISPLAY 0.680851 (2163 1108);
PAINT GREEN (2163 1108);
FORCEPROP 2 LAST CDS_LIB standard
J 0
(2225 1100);
DISPLAY INVISIBLE (2225 1100);
FORCEPROP 1 LAST BODY_TYPE PLUMBING
J 0
(2225 1150);
DISPLAY 0.872340 (2225 1150);
PAINT GREEN (2225 1150);
DISPLAY INVISIBLE (2225 1150);
FORCEPROP 1 LAST HDL_TAP TRUE
J 0
(2550 975);
DISPLAY 0.872340 (2550 975);
DISPLAY INVISIBLE (2550 975);
FORCEPROP 1 LAST PATH I105
J 0
(2223 1100);
DISPLAY 0.872340 (2223 1100);
PAINT GREEN (2223 1100);
DISPLAY INVISIBLE (2223 1100);
FORCEADD TAP..1
(2225 1150);
FORCEPROP 3 LASTPIN (2175 1150) SIG_NAME M_G_CPU1_SB_CA<4>
J 0
(2185 1160);
DISPLAY 0.659574 (2185 1160);
PAINT MONO (2185 1160);
DISPLAY INVISIBLE (2185 1160);
FORCEPROP 1 LASTPIN (2175 1150) BN 4
J 0
(2163 1158);
DISPLAY 0.680851 (2163 1158);
PAINT GREEN (2163 1158);
FORCEPROP 2 LAST CDS_LIB standard
J 0
(2225 1150);
DISPLAY INVISIBLE (2225 1150);
FORCEPROP 1 LAST BODY_TYPE PLUMBING
J 0
(2225 1200);
DISPLAY 0.872340 (2225 1200);
PAINT GREEN (2225 1200);
DISPLAY INVISIBLE (2225 1200);
FORCEPROP 1 LAST HDL_TAP TRUE
J 0
(2550 1025);
DISPLAY 0.872340 (2550 1025);
DISPLAY INVISIBLE (2550 1025);
FORCEPROP 1 LAST PATH I106
J 0
(2223 1150);
DISPLAY 0.872340 (2223 1150);
PAINT GREEN (2223 1150);
DISPLAY INVISIBLE (2223 1150);
FORCEADD TAP..1
(2225 1200);
FORCEPROP 3 LASTPIN (2175 1200) SIG_NAME M_G_CPU1_SB_CA<5>
J 0
(2185 1210);
DISPLAY 0.659574 (2185 1210);
PAINT MONO (2185 1210);
DISPLAY INVISIBLE (2185 1210);
FORCEPROP 1 LASTPIN (2175 1200) BN 5
J 0
(2163 1208);
DISPLAY 0.680851 (2163 1208);
PAINT GREEN (2163 1208);
FORCEPROP 2 LAST CDS_LIB standard
J 0
(2225 1200);
DISPLAY INVISIBLE (2225 1200);
FORCEPROP 1 LAST BODY_TYPE PLUMBING
J 0
(2225 1250);
DISPLAY 0.872340 (2225 1250);
PAINT GREEN (2225 1250);
DISPLAY INVISIBLE (2225 1250);
FORCEPROP 1 LAST HDL_TAP TRUE
J 0
(2550 1075);
DISPLAY 0.872340 (2550 1075);
DISPLAY INVISIBLE (2550 1075);
FORCEPROP 1 LAST PATH I107
J 0
(2223 1200);
DISPLAY 0.872340 (2223 1200);
PAINT GREEN (2223 1200);
DISPLAY INVISIBLE (2223 1200);
FORCEADD TAP..1
(2225 1250);
FORCEPROP 3 LASTPIN (2175 1250) SIG_NAME M_G_CPU1_SB_CA<6>
J 0
(2185 1260);
DISPLAY 0.659574 (2185 1260);
PAINT MONO (2185 1260);
DISPLAY INVISIBLE (2185 1260);
FORCEPROP 1 LASTPIN (2175 1250) BN 6
J 0
(2163 1258);
DISPLAY 0.680851 (2163 1258);
PAINT GREEN (2163 1258);
FORCEPROP 2 LAST CDS_LIB standard
J 0
(2225 1250);
DISPLAY INVISIBLE (2225 1250);
FORCEPROP 1 LAST BODY_TYPE PLUMBING
J 0
(2225 1300);
DISPLAY 0.872340 (2225 1300);
PAINT GREEN (2225 1300);
DISPLAY INVISIBLE (2225 1300);
FORCEPROP 1 LAST HDL_TAP TRUE
J 0
(2550 1125);
DISPLAY 0.872340 (2550 1125);
DISPLAY INVISIBLE (2550 1125);
FORCEPROP 1 LAST PATH I108
J 0
(2223 1250);
DISPLAY 0.872340 (2223 1250);
PAINT GREEN (2223 1250);
DISPLAY INVISIBLE (2223 1250);
FORCEADD TAP..1
(2225 1450);
FORCEPROP 3 LASTPIN (2175 1450) SIG_NAME M_G_CPU1_SA_CA<0>
J 0
(2185 1460);
DISPLAY 0.659574 (2185 1460);
PAINT MONO (2185 1460);
DISPLAY INVISIBLE (2185 1460);
FORCEPROP 1 LASTPIN (2175 1450) BN 0
J 0
(2163 1458);
DISPLAY 0.680851 (2163 1458);
PAINT GREEN (2163 1458);
FORCEPROP 2 LAST CDS_LIB standard
J 0
(2225 1450);
DISPLAY INVISIBLE (2225 1450);
FORCEPROP 1 LAST BODY_TYPE PLUMBING
J 0
(2225 1500);
DISPLAY 0.872340 (2225 1500);
PAINT GREEN (2225 1500);
DISPLAY INVISIBLE (2225 1500);
FORCEPROP 1 LAST HDL_TAP TRUE
J 0
(2550 1325);
DISPLAY 0.872340 (2550 1325);
DISPLAY INVISIBLE (2550 1325);
FORCEPROP 1 LAST PATH I109
J 0
(2223 1450);
DISPLAY 0.872340 (2223 1450);
PAINT GREEN (2223 1450);
DISPLAY INVISIBLE (2223 1450);
FORCEADD TAP..1
R 2
(-1200 200);
FORCEPROP 3 LASTPIN (-1150 200) SIG_NAME M_G_CPU1_SB_CB<2>
J 0
(-1140 210);
DISPLAY 0.659574 (-1140 210);
PAINT MONO (-1140 210);
DISPLAY INVISIBLE (-1140 210);
FORCEPROP 1 LASTPIN (-1150 200) BN 2
J 2
(-1138 208);
DISPLAY 0.680851 (-1138 208);
PAINT GREEN (-1138 208);
FORCEPROP 2 LAST CDS_LIB standard
J 0
(-1200 200);
DISPLAY INVISIBLE (-1200 200);
FORCEPROP 1 LAST BODY_TYPE PLUMBING
J 2
(-1200 250);
DISPLAY 0.872340 (-1200 250);
PAINT GREEN (-1200 250);
DISPLAY INVISIBLE (-1200 250);
FORCEPROP 1 LAST HDL_TAP TRUE
J 2
(-1525 75);
DISPLAY 0.872340 (-1525 75);
DISPLAY INVISIBLE (-1525 75);
FORCEPROP 1 LAST PATH I11
J 2
(-1198 200);
DISPLAY 0.872340 (-1198 200);
PAINT GREEN (-1198 200);
DISPLAY INVISIBLE (-1198 200);
FORCEADD TAP..1
(2225 1500);
FORCEPROP 3 LASTPIN (2175 1500) SIG_NAME M_G_CPU1_SA_CA<1>
J 0
(2185 1510);
DISPLAY 0.659574 (2185 1510);
PAINT MONO (2185 1510);
DISPLAY INVISIBLE (2185 1510);
FORCEPROP 1 LASTPIN (2175 1500) BN 1
J 0
(2163 1508);
DISPLAY 0.680851 (2163 1508);
PAINT GREEN (2163 1508);
FORCEPROP 2 LAST CDS_LIB standard
J 0
(2225 1500);
DISPLAY INVISIBLE (2225 1500);
FORCEPROP 1 LAST BODY_TYPE PLUMBING
J 0
(2225 1550);
DISPLAY 0.872340 (2225 1550);
PAINT GREEN (2225 1550);
DISPLAY INVISIBLE (2225 1550);
FORCEPROP 1 LAST HDL_TAP TRUE
J 0
(2550 1375);
DISPLAY 0.872340 (2550 1375);
DISPLAY INVISIBLE (2550 1375);
FORCEPROP 1 LAST PATH I110
J 0
(2223 1500);
DISPLAY 0.872340 (2223 1500);
PAINT GREEN (2223 1500);
DISPLAY INVISIBLE (2223 1500);
FORCEADD TAP..1
(2225 1550);
FORCEPROP 3 LASTPIN (2175 1550) SIG_NAME M_G_CPU1_SA_CA<2>
J 0
(2185 1560);
DISPLAY 0.659574 (2185 1560);
PAINT MONO (2185 1560);
DISPLAY INVISIBLE (2185 1560);
FORCEPROP 1 LASTPIN (2175 1550) BN 2
J 0
(2163 1558);
DISPLAY 0.680851 (2163 1558);
PAINT GREEN (2163 1558);
FORCEPROP 2 LAST CDS_LIB standard
J 0
(2225 1550);
DISPLAY INVISIBLE (2225 1550);
FORCEPROP 1 LAST BODY_TYPE PLUMBING
J 0
(2225 1600);
DISPLAY 0.872340 (2225 1600);
PAINT GREEN (2225 1600);
DISPLAY INVISIBLE (2225 1600);
FORCEPROP 1 LAST HDL_TAP TRUE
J 0
(2550 1425);
DISPLAY 0.872340 (2550 1425);
DISPLAY INVISIBLE (2550 1425);
FORCEPROP 1 LAST PATH I111
J 0
(2223 1550);
DISPLAY 0.872340 (2223 1550);
PAINT GREEN (2223 1550);
DISPLAY INVISIBLE (2223 1550);
FORCEADD TAP..1
(2225 1600);
FORCEPROP 3 LASTPIN (2175 1600) SIG_NAME M_G_CPU1_SA_CA<3>
J 0
(2185 1610);
DISPLAY 0.659574 (2185 1610);
PAINT MONO (2185 1610);
DISPLAY INVISIBLE (2185 1610);
FORCEPROP 1 LASTPIN (2175 1600) BN 3
J 0
(2163 1608);
DISPLAY 0.680851 (2163 1608);
PAINT GREEN (2163 1608);
FORCEPROP 2 LAST CDS_LIB standard
J 0
(2225 1600);
DISPLAY INVISIBLE (2225 1600);
FORCEPROP 1 LAST BODY_TYPE PLUMBING
J 0
(2225 1650);
DISPLAY 0.872340 (2225 1650);
PAINT GREEN (2225 1650);
DISPLAY INVISIBLE (2225 1650);
FORCEPROP 1 LAST HDL_TAP TRUE
J 0
(2550 1475);
DISPLAY 0.872340 (2550 1475);
DISPLAY INVISIBLE (2550 1475);
FORCEPROP 1 LAST PATH I112
J 0
(2223 1600);
DISPLAY 0.872340 (2223 1600);
PAINT GREEN (2223 1600);
DISPLAY INVISIBLE (2223 1600);
FORCEADD TAP..1
(2225 1650);
FORCEPROP 3 LASTPIN (2175 1650) SIG_NAME M_G_CPU1_SA_CA<4>
J 0
(2185 1660);
DISPLAY 0.659574 (2185 1660);
PAINT MONO (2185 1660);
DISPLAY INVISIBLE (2185 1660);
FORCEPROP 1 LASTPIN (2175 1650) BN 4
J 0
(2163 1658);
DISPLAY 0.680851 (2163 1658);
PAINT GREEN (2163 1658);
FORCEPROP 2 LAST CDS_LIB standard
J 0
(2225 1650);
DISPLAY INVISIBLE (2225 1650);
FORCEPROP 1 LAST BODY_TYPE PLUMBING
J 0
(2225 1700);
DISPLAY 0.872340 (2225 1700);
PAINT GREEN (2225 1700);
DISPLAY INVISIBLE (2225 1700);
FORCEPROP 1 LAST HDL_TAP TRUE
J 0
(2550 1525);
DISPLAY 0.872340 (2550 1525);
DISPLAY INVISIBLE (2550 1525);
FORCEPROP 1 LAST PATH I113
J 0
(2223 1650);
DISPLAY 0.872340 (2223 1650);
PAINT GREEN (2223 1650);
DISPLAY INVISIBLE (2223 1650);
FORCEADD TAP..1
(2225 1700);
FORCEPROP 3 LASTPIN (2175 1700) SIG_NAME M_G_CPU1_SA_CA<5>
J 0
(2185 1710);
DISPLAY 0.659574 (2185 1710);
PAINT MONO (2185 1710);
DISPLAY INVISIBLE (2185 1710);
FORCEPROP 1 LASTPIN (2175 1700) BN 5
J 0
(2163 1708);
DISPLAY 0.680851 (2163 1708);
PAINT GREEN (2163 1708);
FORCEPROP 2 LAST CDS_LIB standard
J 0
(2225 1700);
DISPLAY INVISIBLE (2225 1700);
FORCEPROP 1 LAST BODY_TYPE PLUMBING
J 0
(2225 1750);
DISPLAY 0.872340 (2225 1750);
PAINT GREEN (2225 1750);
DISPLAY INVISIBLE (2225 1750);
FORCEPROP 1 LAST HDL_TAP TRUE
J 0
(2550 1575);
DISPLAY 0.872340 (2550 1575);
DISPLAY INVISIBLE (2550 1575);
FORCEPROP 1 LAST PATH I114
J 0
(2223 1700);
DISPLAY 0.872340 (2223 1700);
PAINT GREEN (2223 1700);
DISPLAY INVISIBLE (2223 1700);
FORCEADD TAP..1
(2225 1750);
FORCEPROP 3 LASTPIN (2175 1750) SIG_NAME M_G_CPU1_SA_CA<6>
J 0
(2185 1760);
DISPLAY 0.659574 (2185 1760);
PAINT MONO (2185 1760);
DISPLAY INVISIBLE (2185 1760);
FORCEPROP 1 LASTPIN (2175 1750) BN 6
J 0
(2163 1758);
DISPLAY 0.680851 (2163 1758);
PAINT GREEN (2163 1758);
FORCEPROP 2 LAST CDS_LIB standard
J 0
(2225 1750);
DISPLAY INVISIBLE (2225 1750);
FORCEPROP 1 LAST BODY_TYPE PLUMBING
J 0
(2225 1800);
DISPLAY 0.872340 (2225 1800);
PAINT GREEN (2225 1800);
DISPLAY INVISIBLE (2225 1800);
FORCEPROP 1 LAST HDL_TAP TRUE
J 0
(2550 1625);
DISPLAY 0.872340 (2550 1625);
DISPLAY INVISIBLE (2550 1625);
FORCEPROP 1 LAST PATH I115
J 0
(2223 1750);
DISPLAY 0.872340 (2223 1750);
PAINT GREEN (2223 1750);
DISPLAY INVISIBLE (2223 1750);
FORCEADD TAP..1
(2225 1900);
FORCEPROP 3 LASTPIN (2175 1900) SIG_NAME M_G_CPU1_SB_DQS_DN<0>
J 0
(2185 1910);
DISPLAY 0.659574 (2185 1910);
PAINT MONO (2185 1910);
DISPLAY INVISIBLE (2185 1910);
FORCEPROP 1 LASTPIN (2175 1900) BN 0
J 0
(2163 1908);
DISPLAY 0.680851 (2163 1908);
PAINT GREEN (2163 1908);
FORCEPROP 2 LAST CDS_LIB standard
J 0
(2225 1900);
DISPLAY INVISIBLE (2225 1900);
FORCEPROP 1 LAST BODY_TYPE PLUMBING
J 0
(2225 1950);
DISPLAY 0.872340 (2225 1950);
PAINT GREEN (2225 1950);
DISPLAY INVISIBLE (2225 1950);
FORCEPROP 1 LAST HDL_TAP TRUE
J 0
(2550 1775);
DISPLAY 0.872340 (2550 1775);
DISPLAY INVISIBLE (2550 1775);
FORCEPROP 1 LAST PATH I116
J 0
(2223 1900);
DISPLAY 0.872340 (2223 1900);
PAINT GREEN (2223 1900);
DISPLAY INVISIBLE (2223 1900);
FORCEADD TAP..1
(2225 1950);
FORCEPROP 3 LASTPIN (2175 1950) SIG_NAME M_G_CPU1_SB_DQS_DN<1>
J 0
(2185 1960);
DISPLAY 0.659574 (2185 1960);
PAINT MONO (2185 1960);
DISPLAY INVISIBLE (2185 1960);
FORCEPROP 1 LASTPIN (2175 1950) BN 1
J 0
(2163 1958);
DISPLAY 0.680851 (2163 1958);
PAINT GREEN (2163 1958);
FORCEPROP 2 LAST CDS_LIB standard
J 0
(2225 1950);
DISPLAY INVISIBLE (2225 1950);
FORCEPROP 1 LAST BODY_TYPE PLUMBING
J 0
(2225 2000);
DISPLAY 0.872340 (2225 2000);
PAINT GREEN (2225 2000);
DISPLAY INVISIBLE (2225 2000);
FORCEPROP 1 LAST HDL_TAP TRUE
J 0
(2550 1825);
DISPLAY 0.872340 (2550 1825);
DISPLAY INVISIBLE (2550 1825);
FORCEPROP 1 LAST PATH I117
J 0
(2223 1950);
DISPLAY 0.872340 (2223 1950);
PAINT GREEN (2223 1950);
DISPLAY INVISIBLE (2223 1950);
FORCEADD TAP..1
(2225 2000);
FORCEPROP 3 LASTPIN (2175 2000) SIG_NAME M_G_CPU1_SB_DQS_DN<2>
J 0
(2185 2010);
DISPLAY 0.659574 (2185 2010);
PAINT MONO (2185 2010);
DISPLAY INVISIBLE (2185 2010);
FORCEPROP 1 LASTPIN (2175 2000) BN 2
J 0
(2163 2008);
DISPLAY 0.680851 (2163 2008);
PAINT GREEN (2163 2008);
FORCEPROP 2 LAST CDS_LIB standard
J 0
(2225 2000);
DISPLAY INVISIBLE (2225 2000);
FORCEPROP 1 LAST BODY_TYPE PLUMBING
J 0
(2225 2050);
DISPLAY 0.872340 (2225 2050);
PAINT GREEN (2225 2050);
DISPLAY INVISIBLE (2225 2050);
FORCEPROP 1 LAST HDL_TAP TRUE
J 0
(2550 1875);
DISPLAY 0.872340 (2550 1875);
DISPLAY INVISIBLE (2550 1875);
FORCEPROP 1 LAST PATH I118
J 0
(2223 2000);
DISPLAY 0.872340 (2223 2000);
PAINT GREEN (2223 2000);
DISPLAY INVISIBLE (2223 2000);
FORCEADD TAP..1
(2225 2050);
FORCEPROP 3 LASTPIN (2175 2050) SIG_NAME M_G_CPU1_SB_DQS_DN<3>
J 0
(2185 2060);
DISPLAY 0.659574 (2185 2060);
PAINT MONO (2185 2060);
DISPLAY INVISIBLE (2185 2060);
FORCEPROP 1 LASTPIN (2175 2050) BN 3
J 0
(2163 2058);
DISPLAY 0.680851 (2163 2058);
PAINT GREEN (2163 2058);
FORCEPROP 2 LAST CDS_LIB standard
J 0
(2225 2050);
DISPLAY INVISIBLE (2225 2050);
FORCEPROP 1 LAST BODY_TYPE PLUMBING
J 0
(2225 2100);
DISPLAY 0.872340 (2225 2100);
PAINT GREEN (2225 2100);
DISPLAY INVISIBLE (2225 2100);
FORCEPROP 1 LAST HDL_TAP TRUE
J 0
(2550 1925);
DISPLAY 0.872340 (2550 1925);
DISPLAY INVISIBLE (2550 1925);
FORCEPROP 1 LAST PATH I119
J 0
(2223 2050);
DISPLAY 0.872340 (2223 2050);
PAINT GREEN (2223 2050);
DISPLAY INVISIBLE (2223 2050);
FORCEADD TAP..1
R 2
(-1200 250);
FORCEPROP 3 LASTPIN (-1150 250) SIG_NAME M_G_CPU1_SB_CB<3>
J 0
(-1140 260);
DISPLAY 0.659574 (-1140 260);
PAINT MONO (-1140 260);
DISPLAY INVISIBLE (-1140 260);
FORCEPROP 1 LASTPIN (-1150 250) BN 3
J 2
(-1138 258);
DISPLAY 0.680851 (-1138 258);
PAINT GREEN (-1138 258);
FORCEPROP 2 LAST CDS_LIB standard
J 0
(-1200 250);
DISPLAY INVISIBLE (-1200 250);
FORCEPROP 1 LAST BODY_TYPE PLUMBING
J 2
(-1200 300);
DISPLAY 0.872340 (-1200 300);
PAINT GREEN (-1200 300);
DISPLAY INVISIBLE (-1200 300);
FORCEPROP 1 LAST HDL_TAP TRUE
J 2
(-1525 125);
DISPLAY 0.872340 (-1525 125);
DISPLAY INVISIBLE (-1525 125);
FORCEPROP 1 LAST PATH I12
J 2
(-1198 250);
DISPLAY 0.872340 (-1198 250);
PAINT GREEN (-1198 250);
DISPLAY INVISIBLE (-1198 250);
FORCEADD TAP..1
(2225 2100);
FORCEPROP 3 LASTPIN (2175 2100) SIG_NAME M_G_CPU1_SB_DQS_DN<4>
J 0
(2185 2110);
DISPLAY 0.659574 (2185 2110);
PAINT MONO (2185 2110);
DISPLAY INVISIBLE (2185 2110);
FORCEPROP 1 LASTPIN (2175 2100) BN 4
J 0
(2163 2108);
DISPLAY 0.680851 (2163 2108);
PAINT GREEN (2163 2108);
FORCEPROP 2 LAST CDS_LIB standard
J 0
(2225 2100);
DISPLAY INVISIBLE (2225 2100);
FORCEPROP 1 LAST BODY_TYPE PLUMBING
J 0
(2225 2150);
DISPLAY 0.872340 (2225 2150);
PAINT GREEN (2225 2150);
DISPLAY INVISIBLE (2225 2150);
FORCEPROP 1 LAST HDL_TAP TRUE
J 0
(2550 1975);
DISPLAY 0.872340 (2550 1975);
DISPLAY INVISIBLE (2550 1975);
FORCEPROP 1 LAST PATH I120
J 0
(2223 2100);
DISPLAY 0.872340 (2223 2100);
PAINT GREEN (2223 2100);
DISPLAY INVISIBLE (2223 2100);
FORCEADD TAP..1
(2225 2150);
FORCEPROP 3 LASTPIN (2175 2150) SIG_NAME M_G_CPU1_SB_DQS_DN<5>
J 0
(2185 2160);
DISPLAY 0.659574 (2185 2160);
PAINT MONO (2185 2160);
DISPLAY INVISIBLE (2185 2160);
FORCEPROP 1 LASTPIN (2175 2150) BN 5
J 0
(2163 2158);
DISPLAY 0.680851 (2163 2158);
PAINT GREEN (2163 2158);
FORCEPROP 2 LAST CDS_LIB standard
J 0
(2225 2150);
DISPLAY INVISIBLE (2225 2150);
FORCEPROP 1 LAST BODY_TYPE PLUMBING
J 0
(2225 2200);
DISPLAY 0.872340 (2225 2200);
PAINT GREEN (2225 2200);
DISPLAY INVISIBLE (2225 2200);
FORCEPROP 1 LAST HDL_TAP TRUE
J 0
(2550 2025);
DISPLAY 0.872340 (2550 2025);
DISPLAY INVISIBLE (2550 2025);
FORCEPROP 1 LAST PATH I121
J 0
(2223 2150);
DISPLAY 0.872340 (2223 2150);
PAINT GREEN (2223 2150);
DISPLAY INVISIBLE (2223 2150);
FORCEADD TAP..1
(2225 2200);
FORCEPROP 3 LASTPIN (2175 2200) SIG_NAME M_G_CPU1_SB_DQS_DN<6>
J 0
(2185 2210);
DISPLAY 0.659574 (2185 2210);
PAINT MONO (2185 2210);
DISPLAY INVISIBLE (2185 2210);
FORCEPROP 1 LASTPIN (2175 2200) BN 6
J 0
(2163 2208);
DISPLAY 0.680851 (2163 2208);
PAINT GREEN (2163 2208);
FORCEPROP 2 LAST CDS_LIB standard
J 0
(2225 2200);
DISPLAY INVISIBLE (2225 2200);
FORCEPROP 1 LAST BODY_TYPE PLUMBING
J 0
(2225 2250);
DISPLAY 0.872340 (2225 2250);
PAINT GREEN (2225 2250);
DISPLAY INVISIBLE (2225 2250);
FORCEPROP 1 LAST HDL_TAP TRUE
J 0
(2550 2075);
DISPLAY 0.872340 (2550 2075);
DISPLAY INVISIBLE (2550 2075);
FORCEPROP 1 LAST PATH I122
J 0
(2223 2200);
DISPLAY 0.872340 (2223 2200);
PAINT GREEN (2223 2200);
DISPLAY INVISIBLE (2223 2200);
FORCEADD TAP..1
(2225 2250);
FORCEPROP 3 LASTPIN (2175 2250) SIG_NAME M_G_CPU1_SB_DQS_DN<7>
J 0
(2185 2260);
DISPLAY 0.659574 (2185 2260);
PAINT MONO (2185 2260);
DISPLAY INVISIBLE (2185 2260);
FORCEPROP 1 LASTPIN (2175 2250) BN 7
J 0
(2163 2258);
DISPLAY 0.680851 (2163 2258);
PAINT GREEN (2163 2258);
FORCEPROP 2 LAST CDS_LIB standard
J 0
(2225 2250);
DISPLAY INVISIBLE (2225 2250);
FORCEPROP 1 LAST BODY_TYPE PLUMBING
J 0
(2225 2300);
DISPLAY 0.872340 (2225 2300);
PAINT GREEN (2225 2300);
DISPLAY INVISIBLE (2225 2300);
FORCEPROP 1 LAST HDL_TAP TRUE
J 0
(2550 2125);
DISPLAY 0.872340 (2550 2125);
DISPLAY INVISIBLE (2550 2125);
FORCEPROP 1 LAST PATH I123
J 0
(2223 2250);
DISPLAY 0.872340 (2223 2250);
PAINT GREEN (2223 2250);
DISPLAY INVISIBLE (2223 2250);
FORCEADD TAP..1
(2225 2300);
FORCEPROP 3 LASTPIN (2175 2300) SIG_NAME M_G_CPU1_SB_DQS_DN<8>
J 0
(2185 2310);
DISPLAY 0.659574 (2185 2310);
PAINT MONO (2185 2310);
DISPLAY INVISIBLE (2185 2310);
FORCEPROP 1 LASTPIN (2175 2300) BN 8
J 0
(2163 2308);
DISPLAY 0.680851 (2163 2308);
PAINT GREEN (2163 2308);
FORCEPROP 2 LAST CDS_LIB standard
J 0
(2225 2300);
DISPLAY INVISIBLE (2225 2300);
FORCEPROP 1 LAST BODY_TYPE PLUMBING
J 0
(2225 2350);
DISPLAY 0.872340 (2225 2350);
PAINT GREEN (2225 2350);
DISPLAY INVISIBLE (2225 2350);
FORCEPROP 1 LAST HDL_TAP TRUE
J 0
(2550 2175);
DISPLAY 0.872340 (2550 2175);
DISPLAY INVISIBLE (2550 2175);
FORCEPROP 1 LAST PATH I124
J 0
(2223 2300);
DISPLAY 0.872340 (2223 2300);
PAINT GREEN (2223 2300);
DISPLAY INVISIBLE (2223 2300);
FORCEADD TAP..1
(2225 2450);
FORCEPROP 3 LASTPIN (2175 2450) SIG_NAME M_G_CPU1_SB_DQS_DP<0>
J 0
(2185 2460);
DISPLAY 0.659574 (2185 2460);
PAINT MONO (2185 2460);
DISPLAY INVISIBLE (2185 2460);
FORCEPROP 1 LASTPIN (2175 2450) BN 0
J 0
(2163 2458);
DISPLAY 0.680851 (2163 2458);
PAINT GREEN (2163 2458);
FORCEPROP 2 LAST CDS_LIB standard
J 0
(2225 2450);
DISPLAY INVISIBLE (2225 2450);
FORCEPROP 1 LAST BODY_TYPE PLUMBING
J 0
(2225 2500);
DISPLAY 0.872340 (2225 2500);
PAINT GREEN (2225 2500);
DISPLAY INVISIBLE (2225 2500);
FORCEPROP 1 LAST HDL_TAP TRUE
J 0
(2550 2325);
DISPLAY 0.872340 (2550 2325);
DISPLAY INVISIBLE (2550 2325);
FORCEPROP 1 LAST PATH I125
J 0
(2223 2450);
DISPLAY 0.872340 (2223 2450);
PAINT GREEN (2223 2450);
DISPLAY INVISIBLE (2223 2450);
FORCEADD TAP..1
(2225 2500);
FORCEPROP 3 LASTPIN (2175 2500) SIG_NAME M_G_CPU1_SB_DQS_DP<1>
J 0
(2185 2510);
DISPLAY 0.659574 (2185 2510);
PAINT MONO (2185 2510);
DISPLAY INVISIBLE (2185 2510);
FORCEPROP 1 LASTPIN (2175 2500) BN 1
J 0
(2163 2508);
DISPLAY 0.680851 (2163 2508);
PAINT GREEN (2163 2508);
FORCEPROP 2 LAST CDS_LIB standard
J 0
(2225 2500);
DISPLAY INVISIBLE (2225 2500);
FORCEPROP 1 LAST BODY_TYPE PLUMBING
J 0
(2225 2550);
DISPLAY 0.872340 (2225 2550);
PAINT GREEN (2225 2550);
DISPLAY INVISIBLE (2225 2550);
FORCEPROP 1 LAST HDL_TAP TRUE
J 0
(2550 2375);
DISPLAY 0.872340 (2550 2375);
DISPLAY INVISIBLE (2550 2375);
FORCEPROP 1 LAST PATH I126
J 0
(2223 2500);
DISPLAY 0.872340 (2223 2500);
PAINT GREEN (2223 2500);
DISPLAY INVISIBLE (2223 2500);
FORCEADD TAP..1
(2225 2550);
FORCEPROP 3 LASTPIN (2175 2550) SIG_NAME M_G_CPU1_SB_DQS_DP<2>
J 0
(2185 2560);
DISPLAY 0.659574 (2185 2560);
PAINT MONO (2185 2560);
DISPLAY INVISIBLE (2185 2560);
FORCEPROP 1 LASTPIN (2175 2550) BN 2
J 0
(2163 2558);
DISPLAY 0.680851 (2163 2558);
PAINT GREEN (2163 2558);
FORCEPROP 2 LAST CDS_LIB standard
J 0
(2225 2550);
DISPLAY INVISIBLE (2225 2550);
FORCEPROP 1 LAST BODY_TYPE PLUMBING
J 0
(2225 2600);
DISPLAY 0.872340 (2225 2600);
PAINT GREEN (2225 2600);
DISPLAY INVISIBLE (2225 2600);
FORCEPROP 1 LAST HDL_TAP TRUE
J 0
(2550 2425);
DISPLAY 0.872340 (2550 2425);
DISPLAY INVISIBLE (2550 2425);
FORCEPROP 1 LAST PATH I127
J 0
(2223 2550);
DISPLAY 0.872340 (2223 2550);
PAINT GREEN (2223 2550);
DISPLAY INVISIBLE (2223 2550);
FORCEADD TAP..1
(2225 2350);
FORCEPROP 3 LASTPIN (2175 2350) SIG_NAME M_G_CPU1_SB_DQS_DN<9>
J 0
(2185 2360);
DISPLAY 0.659574 (2185 2360);
PAINT MONO (2185 2360);
DISPLAY INVISIBLE (2185 2360);
FORCEPROP 1 LASTPIN (2175 2350) BN 9
J 0
(2163 2358);
DISPLAY 0.680851 (2163 2358);
PAINT GREEN (2163 2358);
FORCEPROP 2 LAST CDS_LIB standard
J 0
(2225 2350);
DISPLAY INVISIBLE (2225 2350);
FORCEPROP 1 LAST BODY_TYPE PLUMBING
J 0
(2225 2400);
DISPLAY 0.872340 (2225 2400);
PAINT GREEN (2225 2400);
DISPLAY INVISIBLE (2225 2400);
FORCEPROP 1 LAST HDL_TAP TRUE
J 0
(2550 2225);
DISPLAY 0.872340 (2550 2225);
DISPLAY INVISIBLE (2550 2225);
FORCEPROP 1 LAST PATH I128
J 0
(2223 2350);
DISPLAY 0.872340 (2223 2350);
PAINT GREEN (2223 2350);
DISPLAY INVISIBLE (2223 2350);
FORCEADD TAP..1
(2225 2600);
FORCEPROP 3 LASTPIN (2175 2600) SIG_NAME M_G_CPU1_SB_DQS_DP<3>
J 0
(2185 2610);
DISPLAY 0.659574 (2185 2610);
PAINT MONO (2185 2610);
DISPLAY INVISIBLE (2185 2610);
FORCEPROP 1 LASTPIN (2175 2600) BN 3
J 0
(2163 2608);
DISPLAY 0.680851 (2163 2608);
PAINT GREEN (2163 2608);
FORCEPROP 2 LAST CDS_LIB standard
J 0
(2225 2600);
DISPLAY INVISIBLE (2225 2600);
FORCEPROP 1 LAST BODY_TYPE PLUMBING
J 0
(2225 2650);
DISPLAY 0.872340 (2225 2650);
PAINT GREEN (2225 2650);
DISPLAY INVISIBLE (2225 2650);
FORCEPROP 1 LAST HDL_TAP TRUE
J 0
(2550 2475);
DISPLAY 0.872340 (2550 2475);
DISPLAY INVISIBLE (2550 2475);
FORCEPROP 1 LAST PATH I129
J 0
(2223 2600);
DISPLAY 0.872340 (2223 2600);
PAINT GREEN (2223 2600);
DISPLAY INVISIBLE (2223 2600);
FORCEADD TAP..1
R 2
(-1200 300);
FORCEPROP 3 LASTPIN (-1150 300) SIG_NAME M_G_CPU1_SB_CB<4>
J 0
(-1140 310);
DISPLAY 0.659574 (-1140 310);
PAINT MONO (-1140 310);
DISPLAY INVISIBLE (-1140 310);
FORCEPROP 1 LASTPIN (-1150 300) BN 4
J 2
(-1138 308);
DISPLAY 0.680851 (-1138 308);
PAINT GREEN (-1138 308);
FORCEPROP 2 LAST CDS_LIB standard
J 0
(-1200 300);
DISPLAY INVISIBLE (-1200 300);
FORCEPROP 1 LAST BODY_TYPE PLUMBING
J 2
(-1200 350);
DISPLAY 0.872340 (-1200 350);
PAINT GREEN (-1200 350);
DISPLAY INVISIBLE (-1200 350);
FORCEPROP 1 LAST HDL_TAP TRUE
J 2
(-1525 175);
DISPLAY 0.872340 (-1525 175);
DISPLAY INVISIBLE (-1525 175);
FORCEPROP 1 LAST PATH I13
J 2
(-1198 300);
DISPLAY 0.872340 (-1198 300);
PAINT GREEN (-1198 300);
DISPLAY INVISIBLE (-1198 300);
FORCEADD TAP..1
(2225 2650);
FORCEPROP 3 LASTPIN (2175 2650) SIG_NAME M_G_CPU1_SB_DQS_DP<4>
J 0
(2185 2660);
DISPLAY 0.659574 (2185 2660);
PAINT MONO (2185 2660);
DISPLAY INVISIBLE (2185 2660);
FORCEPROP 1 LASTPIN (2175 2650) BN 4
J 0
(2163 2658);
DISPLAY 0.680851 (2163 2658);
PAINT GREEN (2163 2658);
FORCEPROP 2 LAST CDS_LIB standard
J 0
(2225 2650);
DISPLAY INVISIBLE (2225 2650);
FORCEPROP 1 LAST BODY_TYPE PLUMBING
J 0
(2225 2700);
DISPLAY 0.872340 (2225 2700);
PAINT GREEN (2225 2700);
DISPLAY INVISIBLE (2225 2700);
FORCEPROP 1 LAST HDL_TAP TRUE
J 0
(2550 2525);
DISPLAY 0.872340 (2550 2525);
DISPLAY INVISIBLE (2550 2525);
FORCEPROP 1 LAST PATH I130
J 0
(2223 2650);
DISPLAY 0.872340 (2223 2650);
PAINT GREEN (2223 2650);
DISPLAY INVISIBLE (2223 2650);
FORCEADD TAP..1
(2225 2750);
FORCEPROP 3 LASTPIN (2175 2750) SIG_NAME M_G_CPU1_SB_DQS_DP<6>
J 0
(2185 2760);
DISPLAY 0.659574 (2185 2760);
PAINT MONO (2185 2760);
DISPLAY INVISIBLE (2185 2760);
FORCEPROP 1 LASTPIN (2175 2750) BN 6
J 0
(2163 2758);
DISPLAY 0.680851 (2163 2758);
PAINT GREEN (2163 2758);
FORCEPROP 2 LAST CDS_LIB standard
J 0
(2225 2750);
DISPLAY INVISIBLE (2225 2750);
FORCEPROP 1 LAST BODY_TYPE PLUMBING
J 0
(2225 2800);
DISPLAY 0.872340 (2225 2800);
PAINT GREEN (2225 2800);
DISPLAY INVISIBLE (2225 2800);
FORCEPROP 1 LAST HDL_TAP TRUE
J 0
(2550 2625);
DISPLAY 0.872340 (2550 2625);
DISPLAY INVISIBLE (2550 2625);
FORCEPROP 1 LAST PATH I131
J 0
(2223 2750);
DISPLAY 0.872340 (2223 2750);
PAINT GREEN (2223 2750);
DISPLAY INVISIBLE (2223 2750);
FORCEADD TAP..1
(2225 2800);
FORCEPROP 3 LASTPIN (2175 2800) SIG_NAME M_G_CPU1_SB_DQS_DP<7>
J 0
(2185 2810);
DISPLAY 0.659574 (2185 2810);
PAINT MONO (2185 2810);
DISPLAY INVISIBLE (2185 2810);
FORCEPROP 1 LASTPIN (2175 2800) BN 7
J 0
(2163 2808);
DISPLAY 0.680851 (2163 2808);
PAINT GREEN (2163 2808);
FORCEPROP 2 LAST CDS_LIB standard
J 0
(2225 2800);
DISPLAY INVISIBLE (2225 2800);
FORCEPROP 1 LAST BODY_TYPE PLUMBING
J 0
(2225 2850);
DISPLAY 0.872340 (2225 2850);
PAINT GREEN (2225 2850);
DISPLAY INVISIBLE (2225 2850);
FORCEPROP 1 LAST HDL_TAP TRUE
J 0
(2550 2675);
DISPLAY 0.872340 (2550 2675);
DISPLAY INVISIBLE (2550 2675);
FORCEPROP 1 LAST PATH I132
J 0
(2223 2800);
DISPLAY 0.872340 (2223 2800);
PAINT GREEN (2223 2800);
DISPLAY INVISIBLE (2223 2800);
FORCEADD TAP..1
(2225 2700);
FORCEPROP 3 LASTPIN (2175 2700) SIG_NAME M_G_CPU1_SB_DQS_DP<5>
J 0
(2185 2710);
DISPLAY 0.659574 (2185 2710);
PAINT MONO (2185 2710);
DISPLAY INVISIBLE (2185 2710);
FORCEPROP 1 LASTPIN (2175 2700) BN 5
J 0
(2163 2708);
DISPLAY 0.680851 (2163 2708);
PAINT GREEN (2163 2708);
FORCEPROP 2 LAST CDS_LIB standard
J 0
(2225 2700);
DISPLAY INVISIBLE (2225 2700);
FORCEPROP 1 LAST BODY_TYPE PLUMBING
J 0
(2225 2750);
DISPLAY 0.872340 (2225 2750);
PAINT GREEN (2225 2750);
DISPLAY INVISIBLE (2225 2750);
FORCEPROP 1 LAST HDL_TAP TRUE
J 0
(2550 2575);
DISPLAY 0.872340 (2550 2575);
DISPLAY INVISIBLE (2550 2575);
FORCEPROP 1 LAST PATH I133
J 0
(2223 2700);
DISPLAY 0.872340 (2223 2700);
PAINT GREEN (2223 2700);
DISPLAY INVISIBLE (2223 2700);
FORCEADD TAP..1
(2225 2850);
FORCEPROP 3 LASTPIN (2175 2850) SIG_NAME M_G_CPU1_SB_DQS_DP<8>
J 0
(2185 2860);
DISPLAY 0.659574 (2185 2860);
PAINT MONO (2185 2860);
DISPLAY INVISIBLE (2185 2860);
FORCEPROP 1 LASTPIN (2175 2850) BN 8
J 0
(2163 2858);
DISPLAY 0.680851 (2163 2858);
PAINT GREEN (2163 2858);
FORCEPROP 2 LAST CDS_LIB standard
J 0
(2225 2850);
DISPLAY INVISIBLE (2225 2850);
FORCEPROP 1 LAST BODY_TYPE PLUMBING
J 0
(2225 2900);
DISPLAY 0.872340 (2225 2900);
PAINT GREEN (2225 2900);
DISPLAY INVISIBLE (2225 2900);
FORCEPROP 1 LAST HDL_TAP TRUE
J 0
(2550 2725);
DISPLAY 0.872340 (2550 2725);
DISPLAY INVISIBLE (2550 2725);
FORCEPROP 1 LAST PATH I134
J 0
(2223 2850);
DISPLAY 0.872340 (2223 2850);
PAINT GREEN (2223 2850);
DISPLAY INVISIBLE (2223 2850);
FORCEADD TAP..1
(2225 2900);
FORCEPROP 3 LASTPIN (2175 2900) SIG_NAME M_G_CPU1_SB_DQS_DP<9>
J 0
(2185 2910);
DISPLAY 0.659574 (2185 2910);
PAINT MONO (2185 2910);
DISPLAY INVISIBLE (2185 2910);
FORCEPROP 1 LASTPIN (2175 2900) BN 9
J 0
(2163 2908);
DISPLAY 0.680851 (2163 2908);
PAINT GREEN (2163 2908);
FORCEPROP 2 LAST CDS_LIB standard
J 0
(2225 2900);
DISPLAY INVISIBLE (2225 2900);
FORCEPROP 1 LAST BODY_TYPE PLUMBING
J 0
(2225 2950);
DISPLAY 0.872340 (2225 2950);
PAINT GREEN (2225 2950);
DISPLAY INVISIBLE (2225 2950);
FORCEPROP 1 LAST HDL_TAP TRUE
J 0
(2550 2775);
DISPLAY 0.872340 (2550 2775);
DISPLAY INVISIBLE (2550 2775);
FORCEPROP 1 LAST PATH I135
J 0
(2223 2900);
DISPLAY 0.872340 (2223 2900);
PAINT GREEN (2223 2900);
DISPLAY INVISIBLE (2223 2900);
FORCEADD TAP..1
(2225 3050);
FORCEPROP 3 LASTPIN (2175 3050) SIG_NAME M_G_CPU1_SA_DQS_DN<0>
J 0
(2185 3060);
DISPLAY 0.659574 (2185 3060);
PAINT MONO (2185 3060);
DISPLAY INVISIBLE (2185 3060);
FORCEPROP 1 LASTPIN (2175 3050) BN 0
J 0
(2163 3058);
DISPLAY 0.680851 (2163 3058);
PAINT GREEN (2163 3058);
FORCEPROP 2 LAST CDS_LIB standard
J 0
(2225 3050);
DISPLAY INVISIBLE (2225 3050);
FORCEPROP 1 LAST BODY_TYPE PLUMBING
J 0
(2225 3100);
DISPLAY 0.872340 (2225 3100);
PAINT GREEN (2225 3100);
DISPLAY INVISIBLE (2225 3100);
FORCEPROP 1 LAST HDL_TAP TRUE
J 0
(2550 2925);
DISPLAY 0.872340 (2550 2925);
DISPLAY INVISIBLE (2550 2925);
FORCEPROP 1 LAST PATH I136
J 0
(2223 3050);
DISPLAY 0.872340 (2223 3050);
PAINT GREEN (2223 3050);
DISPLAY INVISIBLE (2223 3050);
FORCEADD TAP..1
(2225 3100);
FORCEPROP 3 LASTPIN (2175 3100) SIG_NAME M_G_CPU1_SA_DQS_DN<1>
J 0
(2185 3110);
DISPLAY 0.659574 (2185 3110);
PAINT MONO (2185 3110);
DISPLAY INVISIBLE (2185 3110);
FORCEPROP 1 LASTPIN (2175 3100) BN 1
J 0
(2163 3108);
DISPLAY 0.680851 (2163 3108);
PAINT GREEN (2163 3108);
FORCEPROP 2 LAST CDS_LIB standard
J 0
(2225 3100);
DISPLAY INVISIBLE (2225 3100);
FORCEPROP 1 LAST BODY_TYPE PLUMBING
J 0
(2225 3150);
DISPLAY 0.872340 (2225 3150);
PAINT GREEN (2225 3150);
DISPLAY INVISIBLE (2225 3150);
FORCEPROP 1 LAST HDL_TAP TRUE
J 0
(2550 2975);
DISPLAY 0.872340 (2550 2975);
DISPLAY INVISIBLE (2550 2975);
FORCEPROP 1 LAST PATH I137
J 0
(2223 3100);
DISPLAY 0.872340 (2223 3100);
PAINT GREEN (2223 3100);
DISPLAY INVISIBLE (2223 3100);
FORCEADD TAP..1
(2225 3150);
FORCEPROP 3 LASTPIN (2175 3150) SIG_NAME M_G_CPU1_SA_DQS_DN<2>
J 0
(2185 3160);
DISPLAY 0.659574 (2185 3160);
PAINT MONO (2185 3160);
DISPLAY INVISIBLE (2185 3160);
FORCEPROP 1 LASTPIN (2175 3150) BN 2
J 0
(2163 3158);
DISPLAY 0.680851 (2163 3158);
PAINT GREEN (2163 3158);
FORCEPROP 2 LAST CDS_LIB standard
J 0
(2225 3150);
DISPLAY INVISIBLE (2225 3150);
FORCEPROP 1 LAST BODY_TYPE PLUMBING
J 0
(2225 3200);
DISPLAY 0.872340 (2225 3200);
PAINT GREEN (2225 3200);
DISPLAY INVISIBLE (2225 3200);
FORCEPROP 1 LAST HDL_TAP TRUE
J 0
(2550 3025);
DISPLAY 0.872340 (2550 3025);
DISPLAY INVISIBLE (2550 3025);
FORCEPROP 1 LAST PATH I138
J 0
(2223 3150);
DISPLAY 0.872340 (2223 3150);
PAINT GREEN (2223 3150);
DISPLAY INVISIBLE (2223 3150);
FORCEADD TAP..1
(2225 3200);
FORCEPROP 3 LASTPIN (2175 3200) SIG_NAME M_G_CPU1_SA_DQS_DN<3>
J 0
(2185 3210);
DISPLAY 0.659574 (2185 3210);
PAINT MONO (2185 3210);
DISPLAY INVISIBLE (2185 3210);
FORCEPROP 1 LASTPIN (2175 3200) BN 3
J 0
(2163 3208);
DISPLAY 0.680851 (2163 3208);
PAINT GREEN (2163 3208);
FORCEPROP 2 LAST CDS_LIB standard
J 0
(2225 3200);
DISPLAY INVISIBLE (2225 3200);
FORCEPROP 1 LAST BODY_TYPE PLUMBING
J 0
(2225 3250);
DISPLAY 0.872340 (2225 3250);
PAINT GREEN (2225 3250);
DISPLAY INVISIBLE (2225 3250);
FORCEPROP 1 LAST HDL_TAP TRUE
J 0
(2550 3075);
DISPLAY 0.872340 (2550 3075);
DISPLAY INVISIBLE (2550 3075);
FORCEPROP 1 LAST PATH I139
J 0
(2223 3200);
DISPLAY 0.872340 (2223 3200);
PAINT GREEN (2223 3200);
DISPLAY INVISIBLE (2223 3200);
FORCEADD TAP..1
R 2
(-1200 350);
FORCEPROP 3 LASTPIN (-1150 350) SIG_NAME M_G_CPU1_SB_CB<5>
J 0
(-1140 360);
DISPLAY 0.659574 (-1140 360);
PAINT MONO (-1140 360);
DISPLAY INVISIBLE (-1140 360);
FORCEPROP 1 LASTPIN (-1150 350) BN 5
J 2
(-1138 358);
DISPLAY 0.680851 (-1138 358);
PAINT GREEN (-1138 358);
FORCEPROP 2 LAST CDS_LIB standard
J 0
(-1200 350);
DISPLAY INVISIBLE (-1200 350);
FORCEPROP 1 LAST BODY_TYPE PLUMBING
J 2
(-1200 400);
DISPLAY 0.872340 (-1200 400);
PAINT GREEN (-1200 400);
DISPLAY INVISIBLE (-1200 400);
FORCEPROP 1 LAST HDL_TAP TRUE
J 2
(-1525 225);
DISPLAY 0.872340 (-1525 225);
DISPLAY INVISIBLE (-1525 225);
FORCEPROP 1 LAST PATH I14
J 2
(-1198 350);
DISPLAY 0.872340 (-1198 350);
PAINT GREEN (-1198 350);
DISPLAY INVISIBLE (-1198 350);
FORCEADD TAP..1
(2225 3250);
FORCEPROP 3 LASTPIN (2175 3250) SIG_NAME M_G_CPU1_SA_DQS_DN<4>
J 0
(2185 3260);
DISPLAY 0.659574 (2185 3260);
PAINT MONO (2185 3260);
DISPLAY INVISIBLE (2185 3260);
FORCEPROP 1 LASTPIN (2175 3250) BN 4
J 0
(2163 3258);
DISPLAY 0.680851 (2163 3258);
PAINT GREEN (2163 3258);
FORCEPROP 2 LAST CDS_LIB standard
J 0
(2225 3250);
DISPLAY INVISIBLE (2225 3250);
FORCEPROP 1 LAST BODY_TYPE PLUMBING
J 0
(2225 3300);
DISPLAY 0.872340 (2225 3300);
PAINT GREEN (2225 3300);
DISPLAY INVISIBLE (2225 3300);
FORCEPROP 1 LAST HDL_TAP TRUE
J 0
(2550 3125);
DISPLAY 0.872340 (2550 3125);
DISPLAY INVISIBLE (2550 3125);
FORCEPROP 1 LAST PATH I140
J 0
(2223 3250);
DISPLAY 0.872340 (2223 3250);
PAINT GREEN (2223 3250);
DISPLAY INVISIBLE (2223 3250);
FORCEADD TAP..1
(2225 3300);
FORCEPROP 3 LASTPIN (2175 3300) SIG_NAME M_G_CPU1_SA_DQS_DN<5>
J 0
(2185 3310);
DISPLAY 0.659574 (2185 3310);
PAINT MONO (2185 3310);
DISPLAY INVISIBLE (2185 3310);
FORCEPROP 1 LASTPIN (2175 3300) BN 5
J 0
(2163 3308);
DISPLAY 0.680851 (2163 3308);
PAINT GREEN (2163 3308);
FORCEPROP 2 LAST CDS_LIB standard
J 0
(2225 3300);
DISPLAY INVISIBLE (2225 3300);
FORCEPROP 1 LAST BODY_TYPE PLUMBING
J 0
(2225 3350);
DISPLAY 0.872340 (2225 3350);
PAINT GREEN (2225 3350);
DISPLAY INVISIBLE (2225 3350);
FORCEPROP 1 LAST HDL_TAP TRUE
J 0
(2550 3175);
DISPLAY 0.872340 (2550 3175);
DISPLAY INVISIBLE (2550 3175);
FORCEPROP 1 LAST PATH I141
J 0
(2223 3300);
DISPLAY 0.872340 (2223 3300);
PAINT GREEN (2223 3300);
DISPLAY INVISIBLE (2223 3300);
FORCEADD TAP..1
(2225 3500);
FORCEPROP 3 LASTPIN (2175 3500) SIG_NAME M_G_CPU1_SA_DQS_DN<9>
J 0
(2185 3510);
DISPLAY 0.659574 (2185 3510);
PAINT MONO (2185 3510);
DISPLAY INVISIBLE (2185 3510);
FORCEPROP 1 LASTPIN (2175 3500) BN 9
J 0
(2163 3508);
DISPLAY 0.680851 (2163 3508);
PAINT GREEN (2163 3508);
FORCEPROP 2 LAST CDS_LIB standard
J 0
(2225 3500);
DISPLAY INVISIBLE (2225 3500);
FORCEPROP 1 LAST BODY_TYPE PLUMBING
J 0
(2225 3550);
DISPLAY 0.872340 (2225 3550);
PAINT GREEN (2225 3550);
DISPLAY INVISIBLE (2225 3550);
FORCEPROP 1 LAST HDL_TAP TRUE
J 0
(2550 3375);
DISPLAY 0.872340 (2550 3375);
DISPLAY INVISIBLE (2550 3375);
FORCEPROP 1 LAST PATH I142
J 0
(2223 3500);
DISPLAY 0.872340 (2223 3500);
PAINT GREEN (2223 3500);
DISPLAY INVISIBLE (2223 3500);
FORCEADD TAP..1
(2225 3450);
FORCEPROP 3 LASTPIN (2175 3450) SIG_NAME M_G_CPU1_SA_DQS_DN<8>
J 0
(2185 3460);
DISPLAY 0.659574 (2185 3460);
PAINT MONO (2185 3460);
DISPLAY INVISIBLE (2185 3460);
FORCEPROP 1 LASTPIN (2175 3450) BN 8
J 0
(2163 3458);
DISPLAY 0.680851 (2163 3458);
PAINT GREEN (2163 3458);
FORCEPROP 2 LAST CDS_LIB standard
J 0
(2225 3450);
DISPLAY INVISIBLE (2225 3450);
FORCEPROP 1 LAST BODY_TYPE PLUMBING
J 0
(2225 3500);
DISPLAY 0.872340 (2225 3500);
PAINT GREEN (2225 3500);
DISPLAY INVISIBLE (2225 3500);
FORCEPROP 1 LAST HDL_TAP TRUE
J 0
(2550 3325);
DISPLAY 0.872340 (2550 3325);
DISPLAY INVISIBLE (2550 3325);
FORCEPROP 1 LAST PATH I143
J 0
(2223 3450);
DISPLAY 0.872340 (2223 3450);
PAINT GREEN (2223 3450);
DISPLAY INVISIBLE (2223 3450);
FORCEADD TAP..1
(2225 3400);
FORCEPROP 3 LASTPIN (2175 3400) SIG_NAME M_G_CPU1_SA_DQS_DN<7>
J 0
(2185 3410);
DISPLAY 0.659574 (2185 3410);
PAINT MONO (2185 3410);
DISPLAY INVISIBLE (2185 3410);
FORCEPROP 1 LASTPIN (2175 3400) BN 7
J 0
(2163 3408);
DISPLAY 0.680851 (2163 3408);
PAINT GREEN (2163 3408);
FORCEPROP 2 LAST CDS_LIB standard
J 0
(2225 3400);
DISPLAY INVISIBLE (2225 3400);
FORCEPROP 1 LAST BODY_TYPE PLUMBING
J 0
(2225 3450);
DISPLAY 0.872340 (2225 3450);
PAINT GREEN (2225 3450);
DISPLAY INVISIBLE (2225 3450);
FORCEPROP 1 LAST HDL_TAP TRUE
J 0
(2550 3275);
DISPLAY 0.872340 (2550 3275);
DISPLAY INVISIBLE (2550 3275);
FORCEPROP 1 LAST PATH I144
J 0
(2223 3400);
DISPLAY 0.872340 (2223 3400);
PAINT GREEN (2223 3400);
DISPLAY INVISIBLE (2223 3400);
FORCEADD TAP..1
(2225 3350);
FORCEPROP 3 LASTPIN (2175 3350) SIG_NAME M_G_CPU1_SA_DQS_DN<6>
J 0
(2185 3360);
DISPLAY 0.659574 (2185 3360);
PAINT MONO (2185 3360);
DISPLAY INVISIBLE (2185 3360);
FORCEPROP 1 LASTPIN (2175 3350) BN 6
J 0
(2163 3358);
DISPLAY 0.680851 (2163 3358);
PAINT GREEN (2163 3358);
FORCEPROP 2 LAST CDS_LIB standard
J 0
(2225 3350);
DISPLAY INVISIBLE (2225 3350);
FORCEPROP 1 LAST BODY_TYPE PLUMBING
J 0
(2225 3400);
DISPLAY 0.872340 (2225 3400);
PAINT GREEN (2225 3400);
DISPLAY INVISIBLE (2225 3400);
FORCEPROP 1 LAST HDL_TAP TRUE
J 0
(2550 3225);
DISPLAY 0.872340 (2550 3225);
DISPLAY INVISIBLE (2550 3225);
FORCEPROP 1 LAST PATH I145
J 0
(2223 3350);
DISPLAY 0.872340 (2223 3350);
PAINT GREEN (2223 3350);
DISPLAY INVISIBLE (2223 3350);
FORCEADD TAP..1
(2225 3600);
FORCEPROP 3 LASTPIN (2175 3600) SIG_NAME M_G_CPU1_SA_DQS_DP<0>
J 0
(2185 3610);
DISPLAY 0.659574 (2185 3610);
PAINT MONO (2185 3610);
DISPLAY INVISIBLE (2185 3610);
FORCEPROP 1 LASTPIN (2175 3600) BN 0
J 0
(2163 3608);
DISPLAY 0.680851 (2163 3608);
PAINT GREEN (2163 3608);
FORCEPROP 2 LAST CDS_LIB standard
J 0
(2225 3600);
DISPLAY INVISIBLE (2225 3600);
FORCEPROP 1 LAST BODY_TYPE PLUMBING
J 0
(2225 3650);
DISPLAY 0.872340 (2225 3650);
PAINT GREEN (2225 3650);
DISPLAY INVISIBLE (2225 3650);
FORCEPROP 1 LAST HDL_TAP TRUE
J 0
(2550 3475);
DISPLAY 0.872340 (2550 3475);
DISPLAY INVISIBLE (2550 3475);
FORCEPROP 1 LAST PATH I146
J 0
(2223 3600);
DISPLAY 0.872340 (2223 3600);
PAINT GREEN (2223 3600);
DISPLAY INVISIBLE (2223 3600);
FORCEADD TAP..1
(2225 3650);
FORCEPROP 3 LASTPIN (2175 3650) SIG_NAME M_G_CPU1_SA_DQS_DP<1>
J 0
(2185 3660);
DISPLAY 0.659574 (2185 3660);
PAINT MONO (2185 3660);
DISPLAY INVISIBLE (2185 3660);
FORCEPROP 1 LASTPIN (2175 3650) BN 1
J 0
(2163 3658);
DISPLAY 0.680851 (2163 3658);
PAINT GREEN (2163 3658);
FORCEPROP 2 LAST CDS_LIB standard
J 0
(2225 3650);
DISPLAY INVISIBLE (2225 3650);
FORCEPROP 1 LAST BODY_TYPE PLUMBING
J 0
(2225 3700);
DISPLAY 0.872340 (2225 3700);
PAINT GREEN (2225 3700);
DISPLAY INVISIBLE (2225 3700);
FORCEPROP 1 LAST HDL_TAP TRUE
J 0
(2550 3525);
DISPLAY 0.872340 (2550 3525);
DISPLAY INVISIBLE (2550 3525);
FORCEPROP 1 LAST PATH I147
J 0
(2223 3650);
DISPLAY 0.872340 (2223 3650);
PAINT GREEN (2223 3650);
DISPLAY INVISIBLE (2223 3650);
FORCEADD TAP..1
(2225 3700);
FORCEPROP 3 LASTPIN (2175 3700) SIG_NAME M_G_CPU1_SA_DQS_DP<2>
J 0
(2185 3710);
DISPLAY 0.659574 (2185 3710);
PAINT MONO (2185 3710);
DISPLAY INVISIBLE (2185 3710);
FORCEPROP 1 LASTPIN (2175 3700) BN 2
J 0
(2163 3708);
DISPLAY 0.680851 (2163 3708);
PAINT GREEN (2163 3708);
FORCEPROP 2 LAST CDS_LIB standard
J 0
(2225 3700);
DISPLAY INVISIBLE (2225 3700);
FORCEPROP 1 LAST BODY_TYPE PLUMBING
J 0
(2225 3750);
DISPLAY 0.872340 (2225 3750);
PAINT GREEN (2225 3750);
DISPLAY INVISIBLE (2225 3750);
FORCEPROP 1 LAST HDL_TAP TRUE
J 0
(2550 3575);
DISPLAY 0.872340 (2550 3575);
DISPLAY INVISIBLE (2550 3575);
FORCEPROP 1 LAST PATH I148
J 0
(2223 3700);
DISPLAY 0.872340 (2223 3700);
PAINT GREEN (2223 3700);
DISPLAY INVISIBLE (2223 3700);
FORCEADD TAP..1
(2225 3750);
FORCEPROP 3 LASTPIN (2175 3750) SIG_NAME M_G_CPU1_SA_DQS_DP<3>
J 0
(2185 3760);
DISPLAY 0.659574 (2185 3760);
PAINT MONO (2185 3760);
DISPLAY INVISIBLE (2185 3760);
FORCEPROP 1 LASTPIN (2175 3750) BN 3
J 0
(2163 3758);
DISPLAY 0.680851 (2163 3758);
PAINT GREEN (2163 3758);
FORCEPROP 2 LAST CDS_LIB standard
J 0
(2225 3750);
DISPLAY INVISIBLE (2225 3750);
FORCEPROP 1 LAST BODY_TYPE PLUMBING
J 0
(2225 3800);
DISPLAY 0.872340 (2225 3800);
PAINT GREEN (2225 3800);
DISPLAY INVISIBLE (2225 3800);
FORCEPROP 1 LAST HDL_TAP TRUE
J 0
(2550 3625);
DISPLAY 0.872340 (2550 3625);
DISPLAY INVISIBLE (2550 3625);
FORCEPROP 1 LAST PATH I149
J 0
(2223 3750);
DISPLAY 0.872340 (2223 3750);
PAINT GREEN (2223 3750);
DISPLAY INVISIBLE (2223 3750);
FORCEADD TAP..1
R 2
(-1200 400);
FORCEPROP 3 LASTPIN (-1150 400) SIG_NAME M_G_CPU1_SB_CB<6>
J 0
(-1140 410);
DISPLAY 0.659574 (-1140 410);
PAINT MONO (-1140 410);
DISPLAY INVISIBLE (-1140 410);
FORCEPROP 1 LASTPIN (-1150 400) BN 6
J 2
(-1138 408);
DISPLAY 0.680851 (-1138 408);
PAINT GREEN (-1138 408);
FORCEPROP 2 LAST CDS_LIB standard
J 0
(-1200 400);
DISPLAY INVISIBLE (-1200 400);
FORCEPROP 1 LAST BODY_TYPE PLUMBING
J 2
(-1200 450);
DISPLAY 0.872340 (-1200 450);
PAINT GREEN (-1200 450);
DISPLAY INVISIBLE (-1200 450);
FORCEPROP 1 LAST HDL_TAP TRUE
J 2
(-1525 275);
DISPLAY 0.872340 (-1525 275);
DISPLAY INVISIBLE (-1525 275);
FORCEPROP 1 LAST PATH I15
J 2
(-1198 400);
DISPLAY 0.872340 (-1198 400);
PAINT GREEN (-1198 400);
DISPLAY INVISIBLE (-1198 400);
FORCEADD TAP..1
(2225 3800);
FORCEPROP 3 LASTPIN (2175 3800) SIG_NAME M_G_CPU1_SA_DQS_DP<4>
J 0
(2185 3810);
DISPLAY 0.659574 (2185 3810);
PAINT MONO (2185 3810);
DISPLAY INVISIBLE (2185 3810);
FORCEPROP 1 LASTPIN (2175 3800) BN 4
J 0
(2163 3808);
DISPLAY 0.680851 (2163 3808);
PAINT GREEN (2163 3808);
FORCEPROP 2 LAST CDS_LIB standard
J 0
(2225 3800);
DISPLAY INVISIBLE (2225 3800);
FORCEPROP 1 LAST BODY_TYPE PLUMBING
J 0
(2225 3850);
DISPLAY 0.872340 (2225 3850);
PAINT GREEN (2225 3850);
DISPLAY INVISIBLE (2225 3850);
FORCEPROP 1 LAST HDL_TAP TRUE
J 0
(2550 3675);
DISPLAY 0.872340 (2550 3675);
DISPLAY INVISIBLE (2550 3675);
FORCEPROP 1 LAST PATH I150
J 0
(2223 3800);
DISPLAY 0.872340 (2223 3800);
PAINT GREEN (2223 3800);
DISPLAY INVISIBLE (2223 3800);
FORCEADD TAP..1
(2225 3850);
FORCEPROP 3 LASTPIN (2175 3850) SIG_NAME M_G_CPU1_SA_DQS_DP<5>
J 0
(2185 3860);
DISPLAY 0.659574 (2185 3860);
PAINT MONO (2185 3860);
DISPLAY INVISIBLE (2185 3860);
FORCEPROP 1 LASTPIN (2175 3850) BN 5
J 0
(2163 3858);
DISPLAY 0.680851 (2163 3858);
PAINT GREEN (2163 3858);
FORCEPROP 2 LAST CDS_LIB standard
J 0
(2225 3850);
DISPLAY INVISIBLE (2225 3850);
FORCEPROP 1 LAST BODY_TYPE PLUMBING
J 0
(2225 3900);
DISPLAY 0.872340 (2225 3900);
PAINT GREEN (2225 3900);
DISPLAY INVISIBLE (2225 3900);
FORCEPROP 1 LAST HDL_TAP TRUE
J 0
(2550 3725);
DISPLAY 0.872340 (2550 3725);
DISPLAY INVISIBLE (2550 3725);
FORCEPROP 1 LAST PATH I151
J 0
(2223 3850);
DISPLAY 0.872340 (2223 3850);
PAINT GREEN (2223 3850);
DISPLAY INVISIBLE (2223 3850);
FORCEADD TAP..1
(2225 3900);
FORCEPROP 3 LASTPIN (2175 3900) SIG_NAME M_G_CPU1_SA_DQS_DP<6>
J 0
(2185 3910);
DISPLAY 0.659574 (2185 3910);
PAINT MONO (2185 3910);
DISPLAY INVISIBLE (2185 3910);
FORCEPROP 1 LASTPIN (2175 3900) BN 6
J 0
(2163 3908);
DISPLAY 0.680851 (2163 3908);
PAINT GREEN (2163 3908);
FORCEPROP 2 LAST CDS_LIB standard
J 0
(2225 3900);
DISPLAY INVISIBLE (2225 3900);
FORCEPROP 1 LAST BODY_TYPE PLUMBING
J 0
(2225 3950);
DISPLAY 0.872340 (2225 3950);
PAINT GREEN (2225 3950);
DISPLAY INVISIBLE (2225 3950);
FORCEPROP 1 LAST HDL_TAP TRUE
J 0
(2550 3775);
DISPLAY 0.872340 (2550 3775);
DISPLAY INVISIBLE (2550 3775);
FORCEPROP 1 LAST PATH I152
J 0
(2223 3900);
DISPLAY 0.872340 (2223 3900);
PAINT GREEN (2223 3900);
DISPLAY INVISIBLE (2223 3900);
FORCEADD TAP..1
(2225 3950);
FORCEPROP 3 LASTPIN (2175 3950) SIG_NAME M_G_CPU1_SA_DQS_DP<7>
J 0
(2185 3960);
DISPLAY 0.659574 (2185 3960);
PAINT MONO (2185 3960);
DISPLAY INVISIBLE (2185 3960);
FORCEPROP 1 LASTPIN (2175 3950) BN 7
J 0
(2163 3958);
DISPLAY 0.680851 (2163 3958);
PAINT GREEN (2163 3958);
FORCEPROP 2 LAST CDS_LIB standard
J 0
(2225 3950);
DISPLAY INVISIBLE (2225 3950);
FORCEPROP 1 LAST BODY_TYPE PLUMBING
J 0
(2225 4000);
DISPLAY 0.872340 (2225 4000);
PAINT GREEN (2225 4000);
DISPLAY INVISIBLE (2225 4000);
FORCEPROP 1 LAST HDL_TAP TRUE
J 0
(2550 3825);
DISPLAY 0.872340 (2550 3825);
DISPLAY INVISIBLE (2550 3825);
FORCEPROP 1 LAST PATH I153
J 0
(2223 3950);
DISPLAY 0.872340 (2223 3950);
PAINT GREEN (2223 3950);
DISPLAY INVISIBLE (2223 3950);
FORCEADD TAP..1
(2225 4000);
FORCEPROP 3 LASTPIN (2175 4000) SIG_NAME M_G_CPU1_SA_DQS_DP<8>
J 0
(2185 4010);
DISPLAY 0.659574 (2185 4010);
PAINT MONO (2185 4010);
DISPLAY INVISIBLE (2185 4010);
FORCEPROP 1 LASTPIN (2175 4000) BN 8
J 0
(2163 4008);
DISPLAY 0.680851 (2163 4008);
PAINT GREEN (2163 4008);
FORCEPROP 2 LAST CDS_LIB standard
J 0
(2225 4000);
DISPLAY INVISIBLE (2225 4000);
FORCEPROP 1 LAST BODY_TYPE PLUMBING
J 0
(2225 4050);
DISPLAY 0.872340 (2225 4050);
PAINT GREEN (2225 4050);
DISPLAY INVISIBLE (2225 4050);
FORCEPROP 1 LAST HDL_TAP TRUE
J 0
(2550 3875);
DISPLAY 0.872340 (2550 3875);
DISPLAY INVISIBLE (2550 3875);
FORCEPROP 1 LAST PATH I154
J 0
(2223 4000);
DISPLAY 0.872340 (2223 4000);
PAINT GREEN (2223 4000);
DISPLAY INVISIBLE (2223 4000);
FORCEADD TAP..1
(2225 4050);
FORCEPROP 3 LASTPIN (2175 4050) SIG_NAME M_G_CPU1_SA_DQS_DP<9>
J 0
(2185 4060);
DISPLAY 0.659574 (2185 4060);
PAINT MONO (2185 4060);
DISPLAY INVISIBLE (2185 4060);
FORCEPROP 1 LASTPIN (2175 4050) BN 9
J 0
(2163 4058);
DISPLAY 0.680851 (2163 4058);
PAINT GREEN (2163 4058);
FORCEPROP 2 LAST CDS_LIB standard
J 0
(2225 4050);
DISPLAY INVISIBLE (2225 4050);
FORCEPROP 1 LAST BODY_TYPE PLUMBING
J 0
(2225 4100);
DISPLAY 0.872340 (2225 4100);
PAINT GREEN (2225 4100);
DISPLAY INVISIBLE (2225 4100);
FORCEPROP 1 LAST HDL_TAP TRUE
J 0
(2550 3925);
DISPLAY 0.872340 (2550 3925);
DISPLAY INVISIBLE (2550 3925);
FORCEPROP 1 LAST PATH I155
J 0
(2223 4050);
DISPLAY 0.872340 (2223 4050);
PAINT GREEN (2223 4050);
DISPLAY INVISIBLE (2223 4050);
FORCEADD OFFPAGE..4
(3325 100);
FORCEPROP 2 LAST $XR0 110 
J 0
(3511 100);
DISPLAY 0.638298 (3511 100);
PAINT MONO (3511 100);
FORCEPROP 2 LAST CDS_LIB standard
J 0
(3325 100);
PAINT MONO (3325 100);
DISPLAY INVISIBLE (3325 100);
FORCEPROP 1 LAST OFFPAGE TRUE
J 0
(3650 -25);
DISPLAY 1.170213 (3650 -25);
PAINT GREEN (3650 -25);
DISPLAY INVISIBLE (3650 -25);
FORCEPROP 1 LAST COMMENT_BODY TRUE
J 0
(3300 0);
DISPLAY 1.170213 (3300 0);
PAINT GREEN (3300 0);
DISPLAY INVISIBLE (3300 0);
FORCEPROP 2 LAST PATH I156
J 0
(3500 175);
DISPLAY 1.021277 (3500 175);
DISPLAY INVISIBLE (3500 175);
FORCEADD OFFPAGE..4
(3325 150);
FORCEPROP 2 LAST $XR0 111 
J 0
(3511 150);
DISPLAY 0.638298 (3511 150);
PAINT MONO (3511 150);
FORCEPROP 2 LAST CDS_LIB standard
J 0
(3325 150);
PAINT MONO (3325 150);
DISPLAY INVISIBLE (3325 150);
FORCEPROP 1 LAST OFFPAGE TRUE
J 0
(3650 25);
DISPLAY 1.170213 (3650 25);
PAINT GREEN (3650 25);
DISPLAY INVISIBLE (3650 25);
FORCEPROP 1 LAST COMMENT_BODY TRUE
J 0
(3300 50);
DISPLAY 1.170213 (3300 50);
PAINT GREEN (3300 50);
DISPLAY INVISIBLE (3300 50);
FORCEPROP 2 LAST PATH I157
J 0
(3500 225);
DISPLAY 1.021277 (3500 225);
DISPLAY INVISIBLE (3500 225);
FORCEADD OFFPAGE..2
(3325 475);
FORCEPROP 2 LAST $XR1 111 
J 0
(3634 475);
DISPLAY 0.638298 (3634 475);
PAINT MONO (3634 475);
FORCEPROP 2 LAST $XR0 110 
J 0
(3514 475);
DISPLAY 0.638298 (3514 475);
PAINT MONO (3514 475);
FORCEPROP 2 LAST CDS_LIB standard
J 0
(3325 475);
PAINT MONO (3325 475);
DISPLAY INVISIBLE (3325 475);
FORCEPROP 1 LAST OFFPAGE TRUE
J 0
(3650 350);
DISPLAY 1.170213 (3650 350);
PAINT GREEN (3650 350);
DISPLAY INVISIBLE (3650 350);
FORCEPROP 1 LAST COMMENT_BODY TRUE
J 0
(3280 380);
DISPLAY 1.170213 (3280 380);
PAINT GREEN (3280 380);
DISPLAY INVISIBLE (3280 380);
FORCEPROP 2 LAST PATH I158
J 0
(3500 550);
DISPLAY 1.021277 (3500 550);
DISPLAY INVISIBLE (3500 550);
FORCEADD OFFPAGE..2
(3325 775);
FORCEPROP 2 LAST $XR1 111 
J 0
(3634 775);
DISPLAY 0.638298 (3634 775);
PAINT MONO (3634 775);
FORCEPROP 2 LAST $XR0 110 
J 0
(3514 775);
DISPLAY 0.638298 (3514 775);
PAINT MONO (3514 775);
FORCEPROP 2 LAST CDS_LIB standard
J 0
(3325 775);
PAINT MONO (3325 775);
DISPLAY INVISIBLE (3325 775);
FORCEPROP 1 LAST OFFPAGE TRUE
J 0
(3650 650);
DISPLAY 1.170213 (3650 650);
PAINT GREEN (3650 650);
DISPLAY INVISIBLE (3650 650);
FORCEPROP 1 LAST COMMENT_BODY TRUE
J 0
(3280 680);
DISPLAY 1.170213 (3280 680);
PAINT GREEN (3280 680);
DISPLAY INVISIBLE (3280 680);
FORCEPROP 2 LAST PATH I159
J 0
(3500 850);
DISPLAY 1.021277 (3500 850);
DISPLAY INVISIBLE (3500 850);
FORCEADD TAP..1
R 2
(-1200 450);
FORCEPROP 3 LASTPIN (-1150 450) SIG_NAME M_G_CPU1_SB_CB<7>
J 0
(-1140 460);
DISPLAY 0.659574 (-1140 460);
PAINT MONO (-1140 460);
DISPLAY INVISIBLE (-1140 460);
FORCEPROP 1 LASTPIN (-1150 450) BN 7
J 2
(-1138 458);
DISPLAY 0.680851 (-1138 458);
PAINT GREEN (-1138 458);
FORCEPROP 2 LAST CDS_LIB standard
J 0
(-1200 450);
DISPLAY INVISIBLE (-1200 450);
FORCEPROP 1 LAST BODY_TYPE PLUMBING
J 2
(-1200 500);
DISPLAY 0.872340 (-1200 500);
PAINT GREEN (-1200 500);
DISPLAY INVISIBLE (-1200 500);
FORCEPROP 1 LAST HDL_TAP TRUE
J 2
(-1525 325);
DISPLAY 0.872340 (-1525 325);
DISPLAY INVISIBLE (-1525 325);
FORCEPROP 1 LAST PATH I16
J 2
(-1198 450);
DISPLAY 0.872340 (-1198 450);
PAINT GREEN (-1198 450);
DISPLAY INVISIBLE (-1198 450);
FORCEADD OFFPAGE..2
(3325 900);
FORCEPROP 2 LAST $XR1 111 
J 0
(3634 900);
DISPLAY 0.638298 (3634 900);
PAINT MONO (3634 900);
FORCEPROP 2 LAST $XR0 110 
J 0
(3514 900);
DISPLAY 0.638298 (3514 900);
PAINT MONO (3514 900);
FORCEPROP 2 LAST CDS_LIB standard
J 0
(3325 900);
PAINT MONO (3325 900);
DISPLAY INVISIBLE (3325 900);
FORCEPROP 1 LAST OFFPAGE TRUE
J 0
(3650 775);
DISPLAY 1.170213 (3650 775);
PAINT GREEN (3650 775);
DISPLAY INVISIBLE (3650 775);
FORCEPROP 1 LAST COMMENT_BODY TRUE
J 0
(3280 805);
DISPLAY 1.170213 (3280 805);
PAINT GREEN (3280 805);
DISPLAY INVISIBLE (3280 805);
FORCEPROP 2 LAST PATH I160
J 0
(3500 975);
DISPLAY 1.021277 (3500 975);
DISPLAY INVISIBLE (3500 975);
FORCEADD OFFPAGE..3
(3325 1275);
FORCEPROP 2 LAST $XR1 111 
J 0
(3659 1275);
DISPLAY 0.638298 (3659 1275);
PAINT MONO (3659 1275);
FORCEPROP 2 LAST $XR0 110 
J 0
(3539 1275);
DISPLAY 0.638298 (3539 1275);
PAINT MONO (3539 1275);
FORCEPROP 2 LAST CDS_LIB standard
J 2
(3325 1275);
DISPLAY INVISIBLE (3325 1275);
FORCEPROP 1 LAST OFFPAGE TRUE
J 0
(3650 1150);
DISPLAY 0.872340 (3650 1150);
DISPLAY INVISIBLE (3650 1150);
FORCEPROP 1 LAST COMMENT_BODY TRUE
J 0
(3275 1175);
DISPLAY 0.872340 (3275 1175);
PAINT GREEN (3275 1175);
DISPLAY INVISIBLE (3275 1175);
FORCEPROP 2 LAST PATH I161
J 0
(3525 1350);
DISPLAY 1.021277 (3525 1350);
DISPLAY INVISIBLE (3525 1350);
FORCEADD OFFPAGE..2
(3325 1400);
FORCEPROP 2 LAST $XR1 111 
J 0
(3634 1400);
DISPLAY 0.638298 (3634 1400);
PAINT MONO (3634 1400);
FORCEPROP 2 LAST $XR0 110 
J 0
(3514 1400);
DISPLAY 0.638298 (3514 1400);
PAINT MONO (3514 1400);
FORCEPROP 2 LAST CDS_LIB standard
J 0
(3325 1400);
PAINT MONO (3325 1400);
DISPLAY INVISIBLE (3325 1400);
FORCEPROP 1 LAST OFFPAGE TRUE
J 0
(3650 1275);
DISPLAY 1.170213 (3650 1275);
PAINT GREEN (3650 1275);
DISPLAY INVISIBLE (3650 1275);
FORCEPROP 1 LAST COMMENT_BODY TRUE
J 0
(3280 1305);
DISPLAY 1.170213 (3280 1305);
PAINT GREEN (3280 1305);
DISPLAY INVISIBLE (3280 1305);
FORCEPROP 2 LAST PATH I162
J 0
(3500 1475);
DISPLAY 1.021277 (3500 1475);
DISPLAY INVISIBLE (3500 1475);
FORCEADD OFFPAGE..3
(3325 1775);
FORCEPROP 2 LAST $XR1 111 
J 0
(3659 1775);
DISPLAY 0.638298 (3659 1775);
PAINT MONO (3659 1775);
FORCEPROP 2 LAST $XR0 110 
J 0
(3539 1775);
DISPLAY 0.638298 (3539 1775);
PAINT MONO (3539 1775);
FORCEPROP 2 LAST CDS_LIB standard
J 2
(3325 1775);
DISPLAY INVISIBLE (3325 1775);
FORCEPROP 1 LAST OFFPAGE TRUE
J 0
(3650 1650);
DISPLAY 0.872340 (3650 1650);
DISPLAY INVISIBLE (3650 1650);
FORCEPROP 1 LAST COMMENT_BODY TRUE
J 0
(3275 1675);
DISPLAY 0.872340 (3275 1675);
PAINT GREEN (3275 1675);
DISPLAY INVISIBLE (3275 1675);
FORCEPROP 2 LAST PATH I163
J 0
(3525 1850);
DISPLAY 1.021277 (3525 1850);
DISPLAY INVISIBLE (3525 1850);
FORCEADD OFFPAGE..3
(3325 2375);
FORCEPROP 2 LAST $XR1 111 
J 0
(3659 2375);
DISPLAY 0.638298 (3659 2375);
PAINT MONO (3659 2375);
FORCEPROP 2 LAST $XR0 110 
J 0
(3539 2375);
DISPLAY 0.638298 (3539 2375);
PAINT MONO (3539 2375);
FORCEPROP 2 LAST CDS_LIB standard
J 2
(3325 2375);
DISPLAY INVISIBLE (3325 2375);
FORCEPROP 1 LAST OFFPAGE TRUE
J 0
(3650 2250);
DISPLAY 0.872340 (3650 2250);
DISPLAY INVISIBLE (3650 2250);
FORCEPROP 1 LAST COMMENT_BODY TRUE
J 0
(3275 2275);
DISPLAY 0.872340 (3275 2275);
PAINT GREEN (3275 2275);
DISPLAY INVISIBLE (3275 2275);
FORCEPROP 2 LAST PATH I164
J 0
(3525 2450);
DISPLAY 1.021277 (3525 2450);
DISPLAY INVISIBLE (3525 2450);
FORCEADD OFFPAGE..3
(3325 2925);
FORCEPROP 2 LAST $XR1 111 
J 0
(3659 2925);
DISPLAY 0.638298 (3659 2925);
PAINT MONO (3659 2925);
FORCEPROP 2 LAST $XR0 110 
J 0
(3539 2925);
DISPLAY 0.638298 (3539 2925);
PAINT MONO (3539 2925);
FORCEPROP 2 LAST CDS_LIB standard
J 2
(3325 2925);
DISPLAY INVISIBLE (3325 2925);
FORCEPROP 1 LAST OFFPAGE TRUE
J 0
(3650 2800);
DISPLAY 0.872340 (3650 2800);
DISPLAY INVISIBLE (3650 2800);
FORCEPROP 1 LAST COMMENT_BODY TRUE
J 0
(3275 2825);
DISPLAY 0.872340 (3275 2825);
PAINT GREEN (3275 2825);
DISPLAY INVISIBLE (3275 2825);
FORCEPROP 2 LAST PATH I165
J 0
(3525 3000);
DISPLAY 1.021277 (3525 3000);
DISPLAY INVISIBLE (3525 3000);
FORCEADD OFFPAGE..3
(3325 3525);
FORCEPROP 2 LAST $XR1 111 
J 0
(3659 3525);
DISPLAY 0.638298 (3659 3525);
PAINT MONO (3659 3525);
FORCEPROP 2 LAST $XR0 110 
J 0
(3539 3525);
DISPLAY 0.638298 (3539 3525);
PAINT MONO (3539 3525);
FORCEPROP 2 LAST CDS_LIB standard
J 2
(3325 3525);
DISPLAY INVISIBLE (3325 3525);
FORCEPROP 1 LAST OFFPAGE TRUE
J 0
(3650 3400);
DISPLAY 0.872340 (3650 3400);
DISPLAY INVISIBLE (3650 3400);
FORCEPROP 1 LAST COMMENT_BODY TRUE
J 0
(3275 3425);
DISPLAY 0.872340 (3275 3425);
PAINT GREEN (3275 3425);
DISPLAY INVISIBLE (3275 3425);
FORCEPROP 2 LAST PATH I166
J 0
(3525 3600);
DISPLAY 1.021277 (3525 3600);
DISPLAY INVISIBLE (3525 3600);
FORCEADD OFFPAGE..3
(3325 4075);
FORCEPROP 2 LAST $XR1 111 
J 0
(3659 4075);
DISPLAY 0.638298 (3659 4075);
PAINT MONO (3659 4075);
FORCEPROP 2 LAST $XR0 110 
J 0
(3539 4075);
DISPLAY 0.638298 (3539 4075);
PAINT MONO (3539 4075);
FORCEPROP 2 LAST CDS_LIB standard
J 2
(3325 4075);
DISPLAY INVISIBLE (3325 4075);
FORCEPROP 1 LAST OFFPAGE TRUE
J 0
(3650 3950);
DISPLAY 0.872340 (3650 3950);
DISPLAY INVISIBLE (3650 3950);
FORCEPROP 1 LAST COMMENT_BODY TRUE
J 0
(3275 3975);
DISPLAY 0.872340 (3275 3975);
PAINT GREEN (3275 3975);
DISPLAY INVISIBLE (3275 3975);
FORCEPROP 2 LAST PATH I167
J 0
(3525 4150);
DISPLAY 1.021277 (3525 4150);
DISPLAY INVISIBLE (3525 4150);
FORCEADD SOCKET4677_AZIF0045P001C01CS..14
(525 1950);
FORCEPROP 1 LAST PART_NUMBER DGA^7000023
J 0
(-575 4300);
DISPLAY 0.723404 (-575 4300);
PAINT GREEN (-575 4300);
DISPLAY INVISIBLE (-575 4300);
FORCEPROP 2 LAST PART_TYPE SMLF
J 0
(-575 4475);
DISPLAY 1.021277 (-575 4475);
FORCEPROP 1 LAST MATERIAL IO
J 0
(-575 4225);
DISPLAY 0.723404 (-575 4225);
PAINT GREEN (-575 4225);
FORCEPROP 2 LAST VALUE SOCKET4677_AZIF0045-P001C01CS
J 0
(-575 4425);
DISPLAY 1.021277 (-575 4425);
FORCEPROP 1 LAST $LOCATION U1
J 0
(-575 4375);
DISPLAY 0.723404 (-575 4375);
PAINT GREEN (-575 4375);
FORCEPROP 0 LASTPIN (1750 100) $PN EA48
J 0
(1760 110);
DISPLAY 0.680851 (1760 110);
PAINT MONO (1760 110);
FORCEPROP 0 LASTPIN (1750 150) $PN DY47
J 0
(1760 160);
DISPLAY 0.680851 (1760 160);
PAINT MONO (1760 160);
FORCEPROP 0 LASTPIN (1750 -150) $PN CW50
J 0
(1760 -140);
DISPLAY 0.680851 (1760 -140);
PAINT MONO (1760 -140);
FORCEPROP 0 LASTPIN (1750 -50) $PN DU48
J 0
(1760 -40);
DISPLAY 0.680851 (1760 -40);
PAINT MONO (1760 -40);
FORCEPROP 0 LASTPIN (1750 0) $PN DV47
J 0
(1760 10);
DISPLAY 0.680851 (1760 10);
PAINT MONO (1760 10);
FORCEPROP 0 LASTPIN (-700 -150) $PN DR45
J 2
(-710 -140);
DISPLAY 0.680851 (-710 -140);
PAINT MONO (-710 -140);
FORCEPROP 0 LASTPIN (-700 -100) $PN DL45
J 2
(-710 -90);
DISPLAY 0.680851 (-710 -90);
PAINT MONO (-710 -90);
FORCEPROP 0 LASTPIN (-700 -50) $PN DN45
J 2
(-710 -40);
DISPLAY 0.680851 (-710 -40);
PAINT MONO (-710 -40);
FORCEPROP 0 LASTPIN (-700 0) $PN DJ45
J 2
(-710 10);
DISPLAY 0.680851 (-710 10);
PAINT MONO (-710 10);
FORCEPROP 0 LASTPIN (1750 1450) $PN DJ52
J 0
(1760 1460);
DISPLAY 0.680851 (1760 1460);
PAINT MONO (1760 1460);
FORCEPROP 0 LASTPIN (1750 1500) $PN DR52
J 0
(1760 1510);
DISPLAY 0.680851 (1760 1510);
PAINT MONO (1760 1510);
FORCEPROP 0 LASTPIN (1750 1550) $PN DK51
J 0
(1760 1560);
DISPLAY 0.680851 (1760 1560);
PAINT MONO (1760 1560);
FORCEPROP 0 LASTPIN (1750 1600) $PN DP51
J 0
(1760 1610);
DISPLAY 0.680851 (1760 1610);
PAINT MONO (1760 1610);
FORCEPROP 0 LASTPIN (1750 1650) $PN DL50
J 0
(1760 1660);
DISPLAY 0.680851 (1760 1660);
PAINT MONO (1760 1660);
FORCEPROP 0 LASTPIN (1750 1700) $PN DN50
J 0
(1760 1710);
DISPLAY 0.680851 (1760 1710);
PAINT MONO (1760 1710);
FORCEPROP 0 LASTPIN (1750 1750) $PN DK44
J 0
(1760 1760);
DISPLAY 0.680851 (1760 1760);
PAINT MONO (1760 1760);
FORCEPROP 0 LASTPIN (-700 2500) $PN DV75
J 2
(-710 2510);
DISPLAY 0.680851 (-710 2510);
PAINT MONO (-710 2510);
FORCEPROP 0 LASTPIN (-700 2550) $PN DU74
J 2
(-710 2560);
DISPLAY 0.680851 (-710 2560);
PAINT MONO (-710 2560);
FORCEPROP 0 LASTPIN (-700 2600) $PN DY75
J 2
(-710 2610);
DISPLAY 0.680851 (-710 2610);
PAINT MONO (-710 2610);
FORCEPROP 0 LASTPIN (-700 2650) $PN EA74
J 2
(-710 2660);
DISPLAY 0.680851 (-710 2660);
PAINT MONO (-710 2660);
FORCEPROP 0 LASTPIN (-700 2700) $PN DU72
J 2
(-710 2710);
DISPLAY 0.680851 (-710 2710);
PAINT MONO (-710 2710);
FORCEPROP 0 LASTPIN (-700 2750) $PN DV71
J 2
(-710 2760);
DISPLAY 0.680851 (-710 2760);
PAINT MONO (-710 2760);
FORCEPROP 0 LASTPIN (-700 2800) $PN EA72
J 2
(-710 2810);
DISPLAY 0.680851 (-710 2810);
PAINT MONO (-710 2810);
FORCEPROP 0 LASTPIN (-700 2850) $PN DY71
J 2
(-710 2860);
DISPLAY 0.680851 (-710 2860);
PAINT MONO (-710 2860);
FORCEPROP 0 LASTPIN (-700 2900) $PN DL72
J 2
(-710 2910);
DISPLAY 0.680851 (-710 2910);
PAINT MONO (-710 2910);
FORCEPROP 0 LASTPIN (-700 2950) $PN DK71
J 2
(-710 2960);
DISPLAY 0.680851 (-710 2960);
PAINT MONO (-710 2960);
FORCEPROP 0 LASTPIN (-700 3000) $PN DN72
J 2
(-710 3010);
DISPLAY 0.680851 (-710 3010);
PAINT MONO (-710 3010);
FORCEPROP 0 LASTPIN (-700 3050) $PN DP71
J 2
(-710 3060);
DISPLAY 0.680851 (-710 3060);
PAINT MONO (-710 3060);
FORCEPROP 0 LASTPIN (-700 3100) $PN DK69
J 2
(-710 3110);
DISPLAY 0.680851 (-710 3110);
PAINT MONO (-710 3110);
FORCEPROP 0 LASTPIN (-700 3150) $PN DL68
J 2
(-710 3160);
DISPLAY 0.680851 (-710 3160);
PAINT MONO (-710 3160);
FORCEPROP 0 LASTPIN (-700 3200) $PN DP69
J 2
(-710 3210);
DISPLAY 0.680851 (-710 3210);
PAINT MONO (-710 3210);
FORCEPROP 0 LASTPIN (-700 3250) $PN DN68
J 2
(-710 3260);
DISPLAY 0.680851 (-710 3260);
PAINT MONO (-710 3260);
FORCEPROP 0 LASTPIN (-700 3300) $PN DV63
J 2
(-710 3310);
DISPLAY 0.680851 (-710 3310);
PAINT MONO (-710 3310);
FORCEPROP 0 LASTPIN (-700 3350) $PN DU62
J 2
(-710 3360);
DISPLAY 0.680851 (-710 3360);
PAINT MONO (-710 3360);
FORCEPROP 0 LASTPIN (-700 3400) $PN DY63
J 2
(-710 3410);
DISPLAY 0.680851 (-710 3410);
PAINT MONO (-710 3410);
FORCEPROP 0 LASTPIN (-700 3450) $PN EA62
J 2
(-710 3460);
DISPLAY 0.680851 (-710 3460);
PAINT MONO (-710 3460);
FORCEPROP 0 LASTPIN (-700 3500) $PN DU60
J 2
(-710 3510);
DISPLAY 0.680851 (-710 3510);
PAINT MONO (-710 3510);
FORCEPROP 0 LASTPIN (-700 3550) $PN DV59
J 2
(-710 3560);
DISPLAY 0.680851 (-710 3560);
PAINT MONO (-710 3560);
FORCEPROP 0 LASTPIN (-700 3600) $PN EA60
J 2
(-710 3610);
DISPLAY 0.680851 (-710 3610);
PAINT MONO (-710 3610);
FORCEPROP 0 LASTPIN (-700 3650) $PN DY59
J 2
(-710 3660);
DISPLAY 0.680851 (-710 3660);
PAINT MONO (-710 3660);
FORCEPROP 0 LASTPIN (-700 3700) $PN DL66
J 2
(-710 3710);
DISPLAY 0.680851 (-710 3710);
PAINT MONO (-710 3710);
FORCEPROP 0 LASTPIN (-700 3750) $PN DK65
J 2
(-710 3760);
DISPLAY 0.680851 (-710 3760);
PAINT MONO (-710 3760);
FORCEPROP 0 LASTPIN (-700 3800) $PN DN66
J 2
(-710 3810);
DISPLAY 0.680851 (-710 3810);
PAINT MONO (-710 3810);
FORCEPROP 0 LASTPIN (-700 3850) $PN DP65
J 2
(-710 3860);
DISPLAY 0.680851 (-710 3860);
PAINT MONO (-710 3860);
FORCEPROP 0 LASTPIN (-700 3900) $PN DK63
J 2
(-710 3910);
DISPLAY 0.680851 (-710 3910);
PAINT MONO (-710 3910);
FORCEPROP 0 LASTPIN (-700 3950) $PN DL62
J 2
(-710 3960);
DISPLAY 0.680851 (-710 3960);
PAINT MONO (-710 3960);
FORCEPROP 0 LASTPIN (-700 4000) $PN DP63
J 2
(-710 4010);
DISPLAY 0.680851 (-710 4010);
PAINT MONO (-710 4010);
FORCEPROP 0 LASTPIN (-700 4050) $PN DN62
J 2
(-710 4060);
DISPLAY 0.680851 (-710 4060);
PAINT MONO (-710 4060);
FORCEPROP 0 LASTPIN (1750 3050) $PN DV73
J 0
(1760 3060);
DISPLAY 0.680851 (1760 3060);
PAINT MONO (1760 3060);
FORCEPROP 0 LASTPIN (1750 3100) $PN DJ70
J 0
(1760 3110);
DISPLAY 0.680851 (1760 3110);
PAINT MONO (1760 3110);
FORCEPROP 0 LASTPIN (1750 3150) $PN DT61
J 0
(1760 3160);
DISPLAY 0.680851 (1760 3160);
PAINT MONO (1760 3160);
FORCEPROP 0 LASTPIN (1750 3200) $PN DL64
J 0
(1760 3210);
DISPLAY 0.680851 (1760 3210);
PAINT MONO (1760 3210);
FORCEPROP 0 LASTPIN (1750 3250) $PN DL58
J 0
(1760 3260);
DISPLAY 0.680851 (1760 3260);
PAINT MONO (1760 3260);
FORCEPROP 0 LASTPIN (1750 3300) $PN EB73
J 0
(1760 3310);
DISPLAY 0.680851 (1760 3310);
PAINT MONO (1760 3310);
FORCEPROP 0 LASTPIN (1750 3350) $PN DR70
J 0
(1760 3360);
DISPLAY 0.680851 (1760 3360);
PAINT MONO (1760 3360);
FORCEPROP 0 LASTPIN (1750 3400) $PN EB61
J 0
(1760 3410);
DISPLAY 0.680851 (1760 3410);
PAINT MONO (1760 3410);
FORCEPROP 0 LASTPIN (1750 3450) $PN DR64
J 0
(1760 3460);
DISPLAY 0.680851 (1760 3460);
PAINT MONO (1760 3460);
FORCEPROP 0 LASTPIN (1750 3500) $PN DR58
J 0
(1760 3510);
DISPLAY 0.680851 (1760 3510);
PAINT MONO (1760 3510);
FORCEPROP 0 LASTPIN (1750 3600) $PN DT73
J 0
(1760 3610);
DISPLAY 0.680851 (1760 3610);
PAINT MONO (1760 3610);
FORCEPROP 0 LASTPIN (1750 3650) $PN DL70
J 0
(1760 3660);
DISPLAY 0.680851 (1760 3660);
PAINT MONO (1760 3660);
FORCEPROP 0 LASTPIN (1750 3700) $PN DV61
J 0
(1760 3710);
DISPLAY 0.680851 (1760 3710);
PAINT MONO (1760 3710);
FORCEPROP 0 LASTPIN (1750 3750) $PN DJ64
J 0
(1760 3760);
DISPLAY 0.680851 (1760 3760);
PAINT MONO (1760 3760);
FORCEPROP 0 LASTPIN (1750 3800) $PN DJ58
J 0
(1760 3810);
DISPLAY 0.680851 (1760 3810);
PAINT MONO (1760 3810);
FORCEPROP 0 LASTPIN (1750 3850) $PN DY73
J 0
(1760 3860);
DISPLAY 0.680851 (1760 3860);
PAINT MONO (1760 3860);
FORCEPROP 0 LASTPIN (1750 3900) $PN DN70
J 0
(1760 3910);
DISPLAY 0.680851 (1760 3910);
PAINT MONO (1760 3910);
FORCEPROP 0 LASTPIN (1750 3950) $PN DY61
J 0
(1760 3960);
DISPLAY 0.680851 (1760 3960);
PAINT MONO (1760 3960);
FORCEPROP 0 LASTPIN (1750 4000) $PN DN64
J 0
(1760 4010);
DISPLAY 0.680851 (1760 4010);
PAINT MONO (1760 4010);
FORCEPROP 0 LASTPIN (1750 4050) $PN DN58
J 0
(1760 4060);
DISPLAY 0.680851 (1760 4060);
PAINT MONO (1760 4060);
FORCEPROP 0 LASTPIN (-700 2100) $PN DL60
J 2
(-710 2110);
DISPLAY 0.680851 (-710 2110);
PAINT MONO (-710 2110);
FORCEPROP 0 LASTPIN (-700 2150) $PN DK59
J 2
(-710 2160);
DISPLAY 0.680851 (-710 2160);
PAINT MONO (-710 2160);
FORCEPROP 0 LASTPIN (-700 2200) $PN DN60
J 2
(-710 2210);
DISPLAY 0.680851 (-710 2210);
PAINT MONO (-710 2210);
FORCEPROP 0 LASTPIN (-700 2250) $PN DP59
J 2
(-710 2260);
DISPLAY 0.680851 (-710 2260);
PAINT MONO (-710 2260);
FORCEPROP 0 LASTPIN (-700 2300) $PN DK57
J 2
(-710 2310);
DISPLAY 0.680851 (-710 2310);
PAINT MONO (-710 2310);
FORCEPROP 0 LASTPIN (-700 2350) $PN DL56
J 2
(-710 2360);
DISPLAY 0.680851 (-710 2360);
PAINT MONO (-710 2360);
FORCEPROP 0 LASTPIN (-700 2400) $PN DP57
J 2
(-710 2410);
DISPLAY 0.680851 (-710 2410);
PAINT MONO (-710 2410);
FORCEPROP 0 LASTPIN (-700 2450) $PN DN56
J 2
(-710 2460);
DISPLAY 0.680851 (-710 2460);
PAINT MONO (-710 2460);
FORCEPROP 0 LASTPIN (1750 1400) $PN DL43
J 0
(1760 1410);
DISPLAY 0.680851 (1760 1410);
PAINT MONO (1760 1410);
FORCEPROP 0 LASTPIN (1750 950) $PN DN43
J 0
(1760 960);
DISPLAY 0.680851 (1760 960);
PAINT MONO (1760 960);
FORCEPROP 0 LASTPIN (1750 1000) $PN DP44
J 0
(1760 1010);
DISPLAY 0.680851 (1760 1010);
PAINT MONO (1760 1010);
FORCEPROP 0 LASTPIN (1750 1050) $PN DV44
J 0
(1760 1060);
DISPLAY 0.680851 (1760 1060);
PAINT MONO (1760 1060);
FORCEPROP 0 LASTPIN (1750 1100) $PN DY44
J 0
(1760 1110);
DISPLAY 0.680851 (1760 1110);
PAINT MONO (1760 1110);
FORCEPROP 0 LASTPIN (1750 1150) $PN DU43
J 0
(1760 1160);
DISPLAY 0.680851 (1760 1160);
PAINT MONO (1760 1160);
FORCEPROP 0 LASTPIN (1750 1200) $PN EA43
J 0
(1760 1210);
DISPLAY 0.680851 (1760 1210);
PAINT MONO (1760 1210);
FORCEPROP 0 LASTPIN (1750 1250) $PN DT42
J 0
(1760 1260);
DISPLAY 0.680851 (1760 1260);
PAINT MONO (1760 1260);
FORCEPROP 0 LASTPIN (-700 500) $PN DL35
J 2
(-710 510);
DISPLAY 0.680851 (-710 510);
PAINT MONO (-710 510);
FORCEPROP 0 LASTPIN (-700 550) $PN DK34
J 2
(-710 560);
DISPLAY 0.680851 (-710 560);
PAINT MONO (-710 560);
FORCEPROP 0 LASTPIN (-700 600) $PN DN35
J 2
(-710 610);
DISPLAY 0.680851 (-710 610);
PAINT MONO (-710 610);
FORCEPROP 0 LASTPIN (-700 650) $PN DP34
J 2
(-710 660);
DISPLAY 0.680851 (-710 660);
PAINT MONO (-710 660);
FORCEPROP 0 LASTPIN (-700 700) $PN DK32
J 2
(-710 710);
DISPLAY 0.680851 (-710 710);
PAINT MONO (-710 710);
FORCEPROP 0 LASTPIN (-700 750) $PN DL31
J 2
(-710 760);
DISPLAY 0.680851 (-710 760);
PAINT MONO (-710 760);
FORCEPROP 0 LASTPIN (-700 800) $PN DP32
J 2
(-710 810);
DISPLAY 0.680851 (-710 810);
PAINT MONO (-710 810);
FORCEPROP 0 LASTPIN (-700 850) $PN DN31
J 2
(-710 860);
DISPLAY 0.680851 (-710 860);
PAINT MONO (-710 860);
FORCEPROP 0 LASTPIN (-700 900) $PN DN29
J 2
(-710 910);
DISPLAY 0.680851 (-710 910);
PAINT MONO (-710 910);
FORCEPROP 0 LASTPIN (-700 950) $PN DK28
J 2
(-710 960);
DISPLAY 0.680851 (-710 960);
PAINT MONO (-710 960);
FORCEPROP 0 LASTPIN (-700 1000) $PN DL29
J 2
(-710 1010);
DISPLAY 0.680851 (-710 1010);
PAINT MONO (-710 1010);
FORCEPROP 0 LASTPIN (-700 1050) $PN DP28
J 2
(-710 1060);
DISPLAY 0.680851 (-710 1060);
PAINT MONO (-710 1060);
FORCEPROP 0 LASTPIN (-700 1100) $PN DK26
J 2
(-710 1110);
DISPLAY 0.680851 (-710 1110);
PAINT MONO (-710 1110);
FORCEPROP 0 LASTPIN (-700 1150) $PN DL25
J 2
(-710 1160);
DISPLAY 0.680851 (-710 1160);
PAINT MONO (-710 1160);
FORCEPROP 0 LASTPIN (-700 1200) $PN DP26
J 2
(-710 1210);
DISPLAY 0.680851 (-710 1210);
PAINT MONO (-710 1210);
FORCEPROP 0 LASTPIN (-700 1250) $PN DN25
J 2
(-710 1260);
DISPLAY 0.680851 (-710 1260);
PAINT MONO (-710 1260);
FORCEPROP 0 LASTPIN (-700 1300) $PN DV26
J 2
(-710 1310);
DISPLAY 0.680851 (-710 1310);
PAINT MONO (-710 1310);
FORCEPROP 0 LASTPIN (-700 1350) $PN DU25
J 2
(-710 1360);
DISPLAY 0.680851 (-710 1360);
PAINT MONO (-710 1360);
FORCEPROP 0 LASTPIN (-700 1400) $PN DY26
J 2
(-710 1410);
DISPLAY 0.680851 (-710 1410);
PAINT MONO (-710 1410);
FORCEPROP 0 LASTPIN (-700 1450) $PN EA25
J 2
(-710 1460);
DISPLAY 0.680851 (-710 1460);
PAINT MONO (-710 1460);
FORCEPROP 0 LASTPIN (-700 1500) $PN DU23
J 2
(-710 1510);
DISPLAY 0.680851 (-710 1510);
PAINT MONO (-710 1510);
FORCEPROP 0 LASTPIN (-700 1550) $PN DV22
J 2
(-710 1560);
DISPLAY 0.680851 (-710 1560);
PAINT MONO (-710 1560);
FORCEPROP 0 LASTPIN (-700 1600) $PN EA23
J 2
(-710 1610);
DISPLAY 0.680851 (-710 1610);
PAINT MONO (-710 1610);
FORCEPROP 0 LASTPIN (-700 1650) $PN DY22
J 2
(-710 1660);
DISPLAY 0.680851 (-710 1660);
PAINT MONO (-710 1660);
FORCEPROP 0 LASTPIN (-700 1700) $PN EK8
J 2
(-710 1710);
DISPLAY 0.680851 (-710 1710);
PAINT MONO (-710 1710);
FORCEPROP 0 LASTPIN (-700 1750) $PN EH8
J 2
(-710 1760);
DISPLAY 0.680851 (-710 1760);
PAINT MONO (-710 1760);
FORCEPROP 0 LASTPIN (-700 1800) $PN EP8
J 2
(-710 1810);
DISPLAY 0.680851 (-710 1810);
PAINT MONO (-710 1810);
FORCEPROP 0 LASTPIN (-700 1850) $PN ET8
J 2
(-710 1860);
DISPLAY 0.680851 (-710 1860);
PAINT MONO (-710 1860);
FORCEPROP 0 LASTPIN (-700 1900) $PN EK6
J 2
(-710 1910);
DISPLAY 0.680851 (-710 1910);
PAINT MONO (-710 1910);
FORCEPROP 0 LASTPIN (-700 1950) $PN EJ5
J 2
(-710 1960);
DISPLAY 0.680851 (-710 1960);
PAINT MONO (-710 1960);
FORCEPROP 0 LASTPIN (-700 2000) $PN EP4
J 2
(-710 2010);
DISPLAY 0.680851 (-710 2010);
PAINT MONO (-710 2010);
FORCEPROP 0 LASTPIN (-700 2050) $PN EM4
J 2
(-710 2060);
DISPLAY 0.680851 (-710 2060);
PAINT MONO (-710 2060);
FORCEPROP 0 LASTPIN (1750 1900) $PN DJ33
J 0
(1760 1910);
DISPLAY 0.680851 (1760 1910);
PAINT MONO (1760 1910);
FORCEPROP 0 LASTPIN (1750 1950) $PN DJ27
J 0
(1760 1960);
DISPLAY 0.680851 (1760 1960);
PAINT MONO (1760 1960);
FORCEPROP 0 LASTPIN (1750 2000) $PN DV24
J 0
(1760 2010);
DISPLAY 0.680851 (1760 2010);
PAINT MONO (1760 2010);
FORCEPROP 0 LASTPIN (1750 2050) $PN EP6
J 0
(1760 2060);
DISPLAY 0.680851 (1760 2060);
PAINT MONO (1760 2060);
FORCEPROP 0 LASTPIN (1750 2100) $PN EB36
J 0
(1760 2110);
DISPLAY 0.680851 (1760 2110);
PAINT MONO (1760 2110);
FORCEPROP 0 LASTPIN (1750 2150) $PN DR33
J 0
(1760 2160);
DISPLAY 0.680851 (1760 2160);
PAINT MONO (1760 2160);
FORCEPROP 0 LASTPIN (1750 2200) $PN DN27
J 0
(1760 2210);
DISPLAY 0.680851 (1760 2210);
PAINT MONO (1760 2210);
FORCEPROP 0 LASTPIN (1750 2250) $PN EB24
J 0
(1760 2260);
DISPLAY 0.680851 (1760 2260);
PAINT MONO (1760 2260);
FORCEPROP 0 LASTPIN (1750 2300) $PN EM6
J 0
(1760 2310);
DISPLAY 0.680851 (1760 2310);
PAINT MONO (1760 2310);
FORCEPROP 0 LASTPIN (1750 2350) $PN DV36
J 0
(1760 2360);
DISPLAY 0.680851 (1760 2360);
PAINT MONO (1760 2360);
FORCEPROP 0 LASTPIN (1750 2450) $PN DL33
J 0
(1760 2460);
DISPLAY 0.680851 (1760 2460);
PAINT MONO (1760 2460);
FORCEPROP 0 LASTPIN (1750 2500) $PN DL27
J 0
(1760 2510);
DISPLAY 0.680851 (1760 2510);
PAINT MONO (1760 2510);
FORCEPROP 0 LASTPIN (1750 2550) $PN DT24
J 0
(1760 2560);
DISPLAY 0.680851 (1760 2560);
PAINT MONO (1760 2560);
FORCEPROP 0 LASTPIN (1750 2600) $PN EN7
J 0
(1760 2610);
DISPLAY 0.680851 (1760 2610);
PAINT MONO (1760 2610);
FORCEPROP 0 LASTPIN (1750 2650) $PN DY36
J 0
(1760 2660);
DISPLAY 0.680851 (1760 2660);
PAINT MONO (1760 2660);
FORCEPROP 0 LASTPIN (1750 2700) $PN DN33
J 0
(1760 2710);
DISPLAY 0.680851 (1760 2710);
PAINT MONO (1760 2710);
FORCEPROP 0 LASTPIN (1750 2750) $PN DR27
J 0
(1760 2760);
DISPLAY 0.680851 (1760 2760);
PAINT MONO (1760 2760);
FORCEPROP 0 LASTPIN (1750 2800) $PN DY24
J 0
(1760 2810);
DISPLAY 0.680851 (1760 2810);
PAINT MONO (1760 2810);
FORCEPROP 0 LASTPIN (1750 2850) $PN EN5
J 0
(1760 2860);
DISPLAY 0.680851 (1760 2860);
PAINT MONO (1760 2860);
FORCEPROP 0 LASTPIN (1750 2900) $PN DT36
J 0
(1760 2910);
DISPLAY 0.680851 (1760 2910);
PAINT MONO (1760 2910);
FORCEPROP 0 LASTPIN (-700 100) $PN DU35
J 2
(-710 110);
DISPLAY 0.680851 (-710 110);
PAINT MONO (-710 110);
FORCEPROP 0 LASTPIN (-700 150) $PN DV34
J 2
(-710 160);
DISPLAY 0.680851 (-710 160);
PAINT MONO (-710 160);
FORCEPROP 0 LASTPIN (-700 200) $PN EA35
J 2
(-710 210);
DISPLAY 0.680851 (-710 210);
PAINT MONO (-710 210);
FORCEPROP 0 LASTPIN (-700 250) $PN DY34
J 2
(-710 260);
DISPLAY 0.680851 (-710 260);
PAINT MONO (-710 260);
FORCEPROP 0 LASTPIN (-700 300) $PN DV38
J 2
(-710 310);
DISPLAY 0.680851 (-710 310);
PAINT MONO (-710 310);
FORCEPROP 0 LASTPIN (-700 350) $PN DU37
J 2
(-710 360);
DISPLAY 0.680851 (-710 360);
PAINT MONO (-710 360);
FORCEPROP 0 LASTPIN (-700 400) $PN DY38
J 2
(-710 410);
DISPLAY 0.680851 (-710 410);
PAINT MONO (-710 410);
FORCEPROP 0 LASTPIN (-700 450) $PN EA37
J 2
(-710 460);
DISPLAY 0.680851 (-710 460);
PAINT MONO (-710 460);
FORCEPROP 0 LASTPIN (1750 900) $PN EB42
J 0
(1760 910);
DISPLAY 0.680851 (1760 910);
PAINT MONO (1760 910);
FORCEPROP 0 LASTPIN (1750 600) $PN DN54
J 0
(1760 610);
DISPLAY 0.680851 (1760 610);
PAINT MONO (1760 610);
FORCEPROP 0 LASTPIN (1750 650) $PN DP53
J 0
(1760 660);
DISPLAY 0.680851 (1760 660);
PAINT MONO (1760 660);
FORCEPROP 0 LASTPIN (1750 700) $PN DL54
J 0
(1760 710);
DISPLAY 0.680851 (1760 710);
PAINT MONO (1760 710);
FORCEPROP 0 LASTPIN (1750 750) $PN DK53
J 0
(1760 760);
DISPLAY 0.680851 (1760 760);
PAINT MONO (1760 760);
FORCEPROP 0 LASTPIN (1750 300) $PN EA41
J 0
(1760 310);
DISPLAY 0.680851 (1760 310);
PAINT MONO (1760 310);
FORCEPROP 0 LASTPIN (1750 350) $PN DY40
J 0
(1760 360);
DISPLAY 0.680851 (1760 360);
PAINT MONO (1760 360);
FORCEPROP 0 LASTPIN (1750 400) $PN DU41
J 0
(1760 410);
DISPLAY 0.680851 (1760 410);
PAINT MONO (1760 410);
FORCEPROP 0 LASTPIN (1750 450) $PN DV40
J 0
(1760 460);
DISPLAY 0.680851 (1760 460);
PAINT MONO (1760 460);
FORCEPROP 2 LAST CDS_LIB pure_quanta
J 0
(525 1950);
DISPLAY INVISIBLE (525 1950);
FORCEPROP 1 LAST NEEDS_NO_SIZE TRUE
J 0
(525 1950);
DISPLAY 0.723404 (525 1950);
PAINT GREEN (525 1950);
DISPLAY INVISIBLE (525 1950);
FORCEPROP 1 LAST CDS_LMAN_SYM_OUTLINE -1100,2250,1050,-2250
J 0
(525 1950);
DISPLAY 0.468085 (525 1950);
PAINT GREEN (525 1950);
DISPLAY INVISIBLE (525 1950);
FORCEPROP 2 LAST CDS_LOCATION U1
J 0
(-575 4525);
DISPLAY 1.021277 (-575 4525);
DISPLAY INVISIBLE (-575 4525);
FORCEPROP 0 LAST $SEC 14
J 0
(-575 4525);
DISPLAY 0.680851 (-575 4525);
PAINT MONO (-575 4525);
DISPLAY INVISIBLE (-575 4525);
FORCEPROP 2 LAST CDS_SEC 14
J 0
(-575 4525);
DISPLAY 1.021277 (-575 4525);
DISPLAY INVISIBLE (-575 4525);
FORCEPROP 1 LAST PATH I168
J 0
(525 1950);
DISPLAY 0.723404 (525 1950);
PAINT GREEN (525 1950);
DISPLAY INVISIBLE (525 1950);
FORCEADD TAP..1
R 2
(-1200 500);
FORCEPROP 3 LASTPIN (-1150 500) SIG_NAME M_G_CPU1_SB_DQ<0>
J 0
(-1140 510);
DISPLAY 0.659574 (-1140 510);
PAINT MONO (-1140 510);
DISPLAY INVISIBLE (-1140 510);
FORCEPROP 1 LASTPIN (-1150 500) BN 0
J 2
(-1138 508);
DISPLAY 0.680851 (-1138 508);
PAINT GREEN (-1138 508);
FORCEPROP 2 LAST CDS_LIB standard
J 0
(-1200 500);
DISPLAY INVISIBLE (-1200 500);
FORCEPROP 1 LAST BODY_TYPE PLUMBING
J 2
(-1200 550);
DISPLAY 0.872340 (-1200 550);
PAINT GREEN (-1200 550);
DISPLAY INVISIBLE (-1200 550);
FORCEPROP 1 LAST HDL_TAP TRUE
J 2
(-1525 375);
DISPLAY 0.872340 (-1525 375);
DISPLAY INVISIBLE (-1525 375);
FORCEPROP 1 LAST PATH I17
J 2
(-1198 500);
DISPLAY 0.872340 (-1198 500);
PAINT GREEN (-1198 500);
DISPLAY INVISIBLE (-1198 500);
FORCEADD TAP..1
R 2
(-1200 550);
FORCEPROP 3 LASTPIN (-1150 550) SIG_NAME M_G_CPU1_SB_DQ<1>
J 0
(-1140 560);
DISPLAY 0.659574 (-1140 560);
PAINT MONO (-1140 560);
DISPLAY INVISIBLE (-1140 560);
FORCEPROP 1 LASTPIN (-1150 550) BN 1
J 2
(-1138 558);
DISPLAY 0.680851 (-1138 558);
PAINT GREEN (-1138 558);
FORCEPROP 2 LAST CDS_LIB standard
J 0
(-1200 550);
DISPLAY INVISIBLE (-1200 550);
FORCEPROP 1 LAST BODY_TYPE PLUMBING
J 2
(-1200 600);
DISPLAY 0.872340 (-1200 600);
PAINT GREEN (-1200 600);
DISPLAY INVISIBLE (-1200 600);
FORCEPROP 1 LAST HDL_TAP TRUE
J 2
(-1525 425);
DISPLAY 0.872340 (-1525 425);
DISPLAY INVISIBLE (-1525 425);
FORCEPROP 1 LAST PATH I18
J 2
(-1198 550);
DISPLAY 0.872340 (-1198 550);
PAINT GREEN (-1198 550);
DISPLAY INVISIBLE (-1198 550);
FORCEADD TAP..1
R 2
(-1200 600);
FORCEPROP 3 LASTPIN (-1150 600) SIG_NAME M_G_CPU1_SB_DQ<2>
J 0
(-1140 610);
DISPLAY 0.659574 (-1140 610);
PAINT MONO (-1140 610);
DISPLAY INVISIBLE (-1140 610);
FORCEPROP 1 LASTPIN (-1150 600) BN 2
J 2
(-1138 608);
DISPLAY 0.680851 (-1138 608);
PAINT GREEN (-1138 608);
FORCEPROP 2 LAST CDS_LIB standard
J 0
(-1200 600);
DISPLAY INVISIBLE (-1200 600);
FORCEPROP 1 LAST BODY_TYPE PLUMBING
J 2
(-1200 650);
DISPLAY 0.872340 (-1200 650);
PAINT GREEN (-1200 650);
DISPLAY INVISIBLE (-1200 650);
FORCEPROP 1 LAST HDL_TAP TRUE
J 2
(-1525 475);
DISPLAY 0.872340 (-1525 475);
DISPLAY INVISIBLE (-1525 475);
FORCEPROP 1 LAST PATH I19
J 2
(-1198 600);
DISPLAY 0.872340 (-1198 600);
PAINT GREEN (-1198 600);
DISPLAY INVISIBLE (-1198 600);
FORCEADD OFFPAGE..2
R 2
(-2225 25);
FORCEPROP 2 LAST $XR1 111 
J 0
(-2600 25);
DISPLAY 0.638298 (-2600 25);
PAINT MONO (-2600 25);
FORCEPROP 2 LAST $XR0 110 
J 0
(-2480 25);
DISPLAY 0.638298 (-2480 25);
PAINT MONO (-2480 25);
FORCEPROP 2 LAST CDS_LIB standard
J 0
(-2225 25);
PAINT MONO (-2225 25);
DISPLAY INVISIBLE (-2225 25);
FORCEPROP 1 LAST OFFPAGE TRUE
J 2
(-2550 -100);
DISPLAY 0.872340 (-2550 -100);
DISPLAY INVISIBLE (-2550 -100);
FORCEPROP 1 LAST COMMENT_BODY TRUE
J 2
(-2180 -70);
DISPLAY 0.872340 (-2180 -70);
PAINT GREEN (-2180 -70);
DISPLAY INVISIBLE (-2180 -70);
FORCEPROP 2 LAST PATH I2
J 0
(-2175 100);
DISPLAY 1.021277 (-2175 100);
DISPLAY INVISIBLE (-2175 100);
FORCEADD TAP..1
R 2
(-1200 700);
FORCEPROP 3 LASTPIN (-1150 700) SIG_NAME M_G_CPU1_SB_DQ<4>
J 0
(-1140 710);
DISPLAY 0.659574 (-1140 710);
PAINT MONO (-1140 710);
DISPLAY INVISIBLE (-1140 710);
FORCEPROP 1 LASTPIN (-1150 700) BN 4
J 2
(-1138 708);
DISPLAY 0.680851 (-1138 708);
PAINT GREEN (-1138 708);
FORCEPROP 2 LAST CDS_LIB standard
J 0
(-1200 700);
DISPLAY INVISIBLE (-1200 700);
FORCEPROP 1 LAST BODY_TYPE PLUMBING
J 2
(-1200 750);
DISPLAY 0.872340 (-1200 750);
PAINT GREEN (-1200 750);
DISPLAY INVISIBLE (-1200 750);
FORCEPROP 1 LAST HDL_TAP TRUE
J 2
(-1525 575);
DISPLAY 0.872340 (-1525 575);
DISPLAY INVISIBLE (-1525 575);
FORCEPROP 1 LAST PATH I20
J 2
(-1198 700);
DISPLAY 0.872340 (-1198 700);
PAINT GREEN (-1198 700);
DISPLAY INVISIBLE (-1198 700);
FORCEADD TAP..1
R 2
(-1200 650);
FORCEPROP 3 LASTPIN (-1150 650) SIG_NAME M_G_CPU1_SB_DQ<3>
J 0
(-1140 660);
DISPLAY 0.659574 (-1140 660);
PAINT MONO (-1140 660);
DISPLAY INVISIBLE (-1140 660);
FORCEPROP 1 LASTPIN (-1150 650) BN 3
J 2
(-1138 658);
DISPLAY 0.680851 (-1138 658);
PAINT GREEN (-1138 658);
FORCEPROP 2 LAST CDS_LIB standard
J 0
(-1200 650);
DISPLAY INVISIBLE (-1200 650);
FORCEPROP 1 LAST BODY_TYPE PLUMBING
J 2
(-1200 700);
DISPLAY 0.872340 (-1200 700);
PAINT GREEN (-1200 700);
DISPLAY INVISIBLE (-1200 700);
FORCEPROP 1 LAST HDL_TAP TRUE
J 2
(-1525 525);
DISPLAY 0.872340 (-1525 525);
DISPLAY INVISIBLE (-1525 525);
FORCEPROP 1 LAST PATH I21
J 2
(-1198 650);
DISPLAY 0.872340 (-1198 650);
PAINT GREEN (-1198 650);
DISPLAY INVISIBLE (-1198 650);
FORCEADD TAP..1
R 2
(-1200 750);
FORCEPROP 3 LASTPIN (-1150 750) SIG_NAME M_G_CPU1_SB_DQ<5>
J 0
(-1140 760);
DISPLAY 0.659574 (-1140 760);
PAINT MONO (-1140 760);
DISPLAY INVISIBLE (-1140 760);
FORCEPROP 1 LASTPIN (-1150 750) BN 5
J 2
(-1138 758);
DISPLAY 0.680851 (-1138 758);
PAINT GREEN (-1138 758);
FORCEPROP 2 LAST CDS_LIB standard
J 0
(-1200 750);
DISPLAY INVISIBLE (-1200 750);
FORCEPROP 1 LAST BODY_TYPE PLUMBING
J 2
(-1200 800);
DISPLAY 0.872340 (-1200 800);
PAINT GREEN (-1200 800);
DISPLAY INVISIBLE (-1200 800);
FORCEPROP 1 LAST HDL_TAP TRUE
J 2
(-1525 625);
DISPLAY 0.872340 (-1525 625);
DISPLAY INVISIBLE (-1525 625);
FORCEPROP 1 LAST PATH I22
J 2
(-1198 750);
DISPLAY 0.872340 (-1198 750);
PAINT GREEN (-1198 750);
DISPLAY INVISIBLE (-1198 750);
FORCEADD TAP..1
R 2
(-1200 800);
FORCEPROP 3 LASTPIN (-1150 800) SIG_NAME M_G_CPU1_SB_DQ<6>
J 0
(-1140 810);
DISPLAY 0.659574 (-1140 810);
PAINT MONO (-1140 810);
DISPLAY INVISIBLE (-1140 810);
FORCEPROP 1 LASTPIN (-1150 800) BN 6
J 2
(-1138 808);
DISPLAY 0.680851 (-1138 808);
PAINT GREEN (-1138 808);
FORCEPROP 2 LAST CDS_LIB standard
J 0
(-1200 800);
DISPLAY INVISIBLE (-1200 800);
FORCEPROP 1 LAST BODY_TYPE PLUMBING
J 2
(-1200 850);
DISPLAY 0.872340 (-1200 850);
PAINT GREEN (-1200 850);
DISPLAY INVISIBLE (-1200 850);
FORCEPROP 1 LAST HDL_TAP TRUE
J 2
(-1525 675);
DISPLAY 0.872340 (-1525 675);
DISPLAY INVISIBLE (-1525 675);
FORCEPROP 1 LAST PATH I23
J 2
(-1198 800);
DISPLAY 0.872340 (-1198 800);
PAINT GREEN (-1198 800);
DISPLAY INVISIBLE (-1198 800);
FORCEADD TAP..1
R 2
(-1200 850);
FORCEPROP 3 LASTPIN (-1150 850) SIG_NAME M_G_CPU1_SB_DQ<7>
J 0
(-1140 860);
DISPLAY 0.659574 (-1140 860);
PAINT MONO (-1140 860);
DISPLAY INVISIBLE (-1140 860);
FORCEPROP 1 LASTPIN (-1150 850) BN 7
J 2
(-1138 858);
DISPLAY 0.680851 (-1138 858);
PAINT GREEN (-1138 858);
FORCEPROP 2 LAST CDS_LIB standard
J 0
(-1200 850);
DISPLAY INVISIBLE (-1200 850);
FORCEPROP 1 LAST BODY_TYPE PLUMBING
J 2
(-1200 900);
DISPLAY 0.872340 (-1200 900);
PAINT GREEN (-1200 900);
DISPLAY INVISIBLE (-1200 900);
FORCEPROP 1 LAST HDL_TAP TRUE
J 2
(-1525 725);
DISPLAY 0.872340 (-1525 725);
DISPLAY INVISIBLE (-1525 725);
FORCEPROP 1 LAST PATH I24
J 2
(-1198 850);
DISPLAY 0.872340 (-1198 850);
PAINT GREEN (-1198 850);
DISPLAY INVISIBLE (-1198 850);
FORCEADD TAP..1
R 2
(-1200 950);
FORCEPROP 3 LASTPIN (-1150 950) SIG_NAME M_G_CPU1_SB_DQ<9>
J 0
(-1140 960);
DISPLAY 0.659574 (-1140 960);
PAINT MONO (-1140 960);
DISPLAY INVISIBLE (-1140 960);
FORCEPROP 1 LASTPIN (-1150 950) BN 9
J 2
(-1138 958);
DISPLAY 0.680851 (-1138 958);
PAINT GREEN (-1138 958);
FORCEPROP 2 LAST CDS_LIB standard
J 0
(-1200 950);
DISPLAY INVISIBLE (-1200 950);
FORCEPROP 1 LAST BODY_TYPE PLUMBING
J 2
(-1200 1000);
DISPLAY 0.872340 (-1200 1000);
PAINT GREEN (-1200 1000);
DISPLAY INVISIBLE (-1200 1000);
FORCEPROP 1 LAST HDL_TAP TRUE
J 2
(-1525 825);
DISPLAY 0.872340 (-1525 825);
DISPLAY INVISIBLE (-1525 825);
FORCEPROP 1 LAST PATH I25
J 2
(-1198 950);
DISPLAY 0.872340 (-1198 950);
PAINT GREEN (-1198 950);
DISPLAY INVISIBLE (-1198 950);
FORCEADD TAP..1
R 2
(-1200 900);
FORCEPROP 3 LASTPIN (-1150 900) SIG_NAME M_G_CPU1_SB_DQ<8>
J 0
(-1140 910);
DISPLAY 0.659574 (-1140 910);
PAINT MONO (-1140 910);
DISPLAY INVISIBLE (-1140 910);
FORCEPROP 1 LASTPIN (-1150 900) BN 8
J 2
(-1138 908);
DISPLAY 0.680851 (-1138 908);
PAINT GREEN (-1138 908);
FORCEPROP 2 LAST CDS_LIB standard
J 0
(-1200 900);
DISPLAY INVISIBLE (-1200 900);
FORCEPROP 1 LAST BODY_TYPE PLUMBING
J 2
(-1200 950);
DISPLAY 0.872340 (-1200 950);
PAINT GREEN (-1200 950);
DISPLAY INVISIBLE (-1200 950);
FORCEPROP 1 LAST HDL_TAP TRUE
J 2
(-1525 775);
DISPLAY 0.872340 (-1525 775);
DISPLAY INVISIBLE (-1525 775);
FORCEPROP 1 LAST PATH I26
J 2
(-1198 900);
DISPLAY 0.872340 (-1198 900);
PAINT GREEN (-1198 900);
DISPLAY INVISIBLE (-1198 900);
FORCEADD TAP..1
R 2
(-1200 1000);
FORCEPROP 3 LASTPIN (-1150 1000) SIG_NAME M_G_CPU1_SB_DQ<10>
J 0
(-1140 1010);
DISPLAY 0.659574 (-1140 1010);
PAINT MONO (-1140 1010);
DISPLAY INVISIBLE (-1140 1010);
FORCEPROP 1 LASTPIN (-1150 1000) BN 10
J 2
(-1138 1008);
DISPLAY 0.680851 (-1138 1008);
PAINT GREEN (-1138 1008);
FORCEPROP 2 LAST CDS_LIB standard
J 0
(-1200 1000);
DISPLAY INVISIBLE (-1200 1000);
FORCEPROP 1 LAST BODY_TYPE PLUMBING
J 2
(-1200 1050);
DISPLAY 0.872340 (-1200 1050);
PAINT GREEN (-1200 1050);
DISPLAY INVISIBLE (-1200 1050);
FORCEPROP 1 LAST HDL_TAP TRUE
J 2
(-1525 875);
DISPLAY 0.872340 (-1525 875);
DISPLAY INVISIBLE (-1525 875);
FORCEPROP 1 LAST PATH I27
J 2
(-1198 1000);
DISPLAY 0.872340 (-1198 1000);
PAINT GREEN (-1198 1000);
DISPLAY INVISIBLE (-1198 1000);
FORCEADD TAP..1
R 2
(-1200 1050);
FORCEPROP 3 LASTPIN (-1150 1050) SIG_NAME M_G_CPU1_SB_DQ<11>
J 0
(-1140 1060);
DISPLAY 0.659574 (-1140 1060);
PAINT MONO (-1140 1060);
DISPLAY INVISIBLE (-1140 1060);
FORCEPROP 1 LASTPIN (-1150 1050) BN 11
J 2
(-1138 1058);
DISPLAY 0.680851 (-1138 1058);
PAINT GREEN (-1138 1058);
FORCEPROP 2 LAST CDS_LIB standard
J 0
(-1200 1050);
DISPLAY INVISIBLE (-1200 1050);
FORCEPROP 1 LAST BODY_TYPE PLUMBING
J 2
(-1200 1100);
DISPLAY 0.872340 (-1200 1100);
PAINT GREEN (-1200 1100);
DISPLAY INVISIBLE (-1200 1100);
FORCEPROP 1 LAST HDL_TAP TRUE
J 2
(-1525 925);
DISPLAY 0.872340 (-1525 925);
DISPLAY INVISIBLE (-1525 925);
FORCEPROP 1 LAST PATH I28
J 2
(-1198 1050);
DISPLAY 0.872340 (-1198 1050);
PAINT GREEN (-1198 1050);
DISPLAY INVISIBLE (-1198 1050);
FORCEADD TAP..1
R 2
(-1200 1100);
FORCEPROP 3 LASTPIN (-1150 1100) SIG_NAME M_G_CPU1_SB_DQ<12>
J 0
(-1140 1110);
DISPLAY 0.659574 (-1140 1110);
PAINT MONO (-1140 1110);
DISPLAY INVISIBLE (-1140 1110);
FORCEPROP 1 LASTPIN (-1150 1100) BN 12
J 2
(-1138 1108);
DISPLAY 0.680851 (-1138 1108);
PAINT GREEN (-1138 1108);
FORCEPROP 2 LAST CDS_LIB standard
J 0
(-1200 1100);
DISPLAY INVISIBLE (-1200 1100);
FORCEPROP 1 LAST BODY_TYPE PLUMBING
J 2
(-1200 1150);
DISPLAY 0.872340 (-1200 1150);
PAINT GREEN (-1200 1150);
DISPLAY INVISIBLE (-1200 1150);
FORCEPROP 1 LAST HDL_TAP TRUE
J 2
(-1525 975);
DISPLAY 0.872340 (-1525 975);
DISPLAY INVISIBLE (-1525 975);
FORCEPROP 1 LAST PATH I29
J 2
(-1198 1100);
DISPLAY 0.872340 (-1198 1100);
PAINT GREEN (-1198 1100);
DISPLAY INVISIBLE (-1198 1100);
FORCEADD TAP..1
R 2
(-1200 -150);
FORCEPROP 3 LASTPIN (-1150 -150) SIG_NAME M_G_CPU1_CLK_DN<0>
J 0
(-1140 -140);
DISPLAY 0.659574 (-1140 -140);
PAINT MONO (-1140 -140);
DISPLAY INVISIBLE (-1140 -140);
FORCEPROP 1 LASTPIN (-1150 -150) BN 0
J 2
(-1138 -142);
DISPLAY 0.680851 (-1138 -142);
PAINT GREEN (-1138 -142);
FORCEPROP 2 LAST CDS_LIB standard
J 0
(-1200 -150);
DISPLAY INVISIBLE (-1200 -150);
FORCEPROP 1 LAST BODY_TYPE PLUMBING
J 2
(-1200 -100);
DISPLAY 0.872340 (-1200 -100);
PAINT GREEN (-1200 -100);
DISPLAY INVISIBLE (-1200 -100);
FORCEPROP 1 LAST HDL_TAP TRUE
J 2
(-1525 -275);
DISPLAY 0.872340 (-1525 -275);
DISPLAY INVISIBLE (-1525 -275);
FORCEPROP 1 LAST PATH I3
J 2
(-1198 -150);
DISPLAY 0.872340 (-1198 -150);
PAINT GREEN (-1198 -150);
DISPLAY INVISIBLE (-1198 -150);
FORCEADD TAP..1
R 2
(-1200 1150);
FORCEPROP 3 LASTPIN (-1150 1150) SIG_NAME M_G_CPU1_SB_DQ<13>
J 0
(-1140 1160);
DISPLAY 0.659574 (-1140 1160);
PAINT MONO (-1140 1160);
DISPLAY INVISIBLE (-1140 1160);
FORCEPROP 1 LASTPIN (-1150 1150) BN 13
J 2
(-1138 1158);
DISPLAY 0.680851 (-1138 1158);
PAINT GREEN (-1138 1158);
FORCEPROP 2 LAST CDS_LIB standard
J 0
(-1200 1150);
DISPLAY INVISIBLE (-1200 1150);
FORCEPROP 1 LAST BODY_TYPE PLUMBING
J 2
(-1200 1200);
DISPLAY 0.872340 (-1200 1200);
PAINT GREEN (-1200 1200);
DISPLAY INVISIBLE (-1200 1200);
FORCEPROP 1 LAST HDL_TAP TRUE
J 2
(-1525 1025);
DISPLAY 0.872340 (-1525 1025);
DISPLAY INVISIBLE (-1525 1025);
FORCEPROP 1 LAST PATH I30
J 2
(-1198 1150);
DISPLAY 0.872340 (-1198 1150);
PAINT GREEN (-1198 1150);
DISPLAY INVISIBLE (-1198 1150);
FORCEADD TAP..1
R 2
(-1200 1200);
FORCEPROP 3 LASTPIN (-1150 1200) SIG_NAME M_G_CPU1_SB_DQ<14>
J 0
(-1140 1210);
DISPLAY 0.659574 (-1140 1210);
PAINT MONO (-1140 1210);
DISPLAY INVISIBLE (-1140 1210);
FORCEPROP 1 LASTPIN (-1150 1200) BN 14
J 2
(-1138 1208);
DISPLAY 0.680851 (-1138 1208);
PAINT GREEN (-1138 1208);
FORCEPROP 2 LAST CDS_LIB standard
J 0
(-1200 1200);
DISPLAY INVISIBLE (-1200 1200);
FORCEPROP 1 LAST BODY_TYPE PLUMBING
J 2
(-1200 1250);
DISPLAY 0.872340 (-1200 1250);
PAINT GREEN (-1200 1250);
DISPLAY INVISIBLE (-1200 1250);
FORCEPROP 1 LAST HDL_TAP TRUE
J 2
(-1525 1075);
DISPLAY 0.872340 (-1525 1075);
DISPLAY INVISIBLE (-1525 1075);
FORCEPROP 1 LAST PATH I31
J 2
(-1198 1200);
DISPLAY 0.872340 (-1198 1200);
PAINT GREEN (-1198 1200);
DISPLAY INVISIBLE (-1198 1200);
FORCEADD TAP..1
R 2
(-1200 1250);
FORCEPROP 3 LASTPIN (-1150 1250) SIG_NAME M_G_CPU1_SB_DQ<15>
J 0
(-1140 1260);
DISPLAY 0.659574 (-1140 1260);
PAINT MONO (-1140 1260);
DISPLAY INVISIBLE (-1140 1260);
FORCEPROP 1 LASTPIN (-1150 1250) BN 15
J 2
(-1138 1258);
DISPLAY 0.680851 (-1138 1258);
PAINT GREEN (-1138 1258);
FORCEPROP 2 LAST CDS_LIB standard
J 0
(-1200 1250);
DISPLAY INVISIBLE (-1200 1250);
FORCEPROP 1 LAST BODY_TYPE PLUMBING
J 2
(-1200 1300);
DISPLAY 0.872340 (-1200 1300);
PAINT GREEN (-1200 1300);
DISPLAY INVISIBLE (-1200 1300);
FORCEPROP 1 LAST HDL_TAP TRUE
J 2
(-1525 1125);
DISPLAY 0.872340 (-1525 1125);
DISPLAY INVISIBLE (-1525 1125);
FORCEPROP 1 LAST PATH I32
J 2
(-1198 1250);
DISPLAY 0.872340 (-1198 1250);
PAINT GREEN (-1198 1250);
DISPLAY INVISIBLE (-1198 1250);
FORCEADD TAP..1
R 2
(-1200 1300);
FORCEPROP 3 LASTPIN (-1150 1300) SIG_NAME M_G_CPU1_SB_DQ<16>
J 0
(-1140 1310);
DISPLAY 0.659574 (-1140 1310);
PAINT MONO (-1140 1310);
DISPLAY INVISIBLE (-1140 1310);
FORCEPROP 1 LASTPIN (-1150 1300) BN 16
J 2
(-1138 1308);
DISPLAY 0.680851 (-1138 1308);
PAINT GREEN (-1138 1308);
FORCEPROP 2 LAST CDS_LIB standard
J 0
(-1200 1300);
DISPLAY INVISIBLE (-1200 1300);
FORCEPROP 1 LAST BODY_TYPE PLUMBING
J 2
(-1200 1350);
DISPLAY 0.872340 (-1200 1350);
PAINT GREEN (-1200 1350);
DISPLAY INVISIBLE (-1200 1350);
FORCEPROP 1 LAST HDL_TAP TRUE
J 2
(-1525 1175);
DISPLAY 0.872340 (-1525 1175);
DISPLAY INVISIBLE (-1525 1175);
FORCEPROP 1 LAST PATH I33
J 2
(-1198 1300);
DISPLAY 0.872340 (-1198 1300);
PAINT GREEN (-1198 1300);
DISPLAY INVISIBLE (-1198 1300);
FORCEADD TAP..1
R 2
(-1200 1350);
FORCEPROP 3 LASTPIN (-1150 1350) SIG_NAME M_G_CPU1_SB_DQ<17>
J 0
(-1140 1360);
DISPLAY 0.659574 (-1140 1360);
PAINT MONO (-1140 1360);
DISPLAY INVISIBLE (-1140 1360);
FORCEPROP 1 LASTPIN (-1150 1350) BN 17
J 2
(-1138 1358);
DISPLAY 0.680851 (-1138 1358);
PAINT GREEN (-1138 1358);
FORCEPROP 2 LAST CDS_LIB standard
J 0
(-1200 1350);
DISPLAY INVISIBLE (-1200 1350);
FORCEPROP 1 LAST BODY_TYPE PLUMBING
J 2
(-1200 1400);
DISPLAY 0.872340 (-1200 1400);
PAINT GREEN (-1200 1400);
DISPLAY INVISIBLE (-1200 1400);
FORCEPROP 1 LAST HDL_TAP TRUE
J 2
(-1525 1225);
DISPLAY 0.872340 (-1525 1225);
DISPLAY INVISIBLE (-1525 1225);
FORCEPROP 1 LAST PATH I34
J 2
(-1198 1350);
DISPLAY 0.872340 (-1198 1350);
PAINT GREEN (-1198 1350);
DISPLAY INVISIBLE (-1198 1350);
FORCEADD TAP..1
R 2
(-1200 1400);
FORCEPROP 3 LASTPIN (-1150 1400) SIG_NAME M_G_CPU1_SB_DQ<18>
J 0
(-1140 1410);
DISPLAY 0.659574 (-1140 1410);
PAINT MONO (-1140 1410);
DISPLAY INVISIBLE (-1140 1410);
FORCEPROP 1 LASTPIN (-1150 1400) BN 18
J 2
(-1138 1408);
DISPLAY 0.680851 (-1138 1408);
PAINT GREEN (-1138 1408);
FORCEPROP 2 LAST CDS_LIB standard
J 0
(-1200 1400);
DISPLAY INVISIBLE (-1200 1400);
FORCEPROP 1 LAST BODY_TYPE PLUMBING
J 2
(-1200 1450);
DISPLAY 0.872340 (-1200 1450);
PAINT GREEN (-1200 1450);
DISPLAY INVISIBLE (-1200 1450);
FORCEPROP 1 LAST HDL_TAP TRUE
J 2
(-1525 1275);
DISPLAY 0.872340 (-1525 1275);
DISPLAY INVISIBLE (-1525 1275);
FORCEPROP 1 LAST PATH I35
J 2
(-1198 1400);
DISPLAY 0.872340 (-1198 1400);
PAINT GREEN (-1198 1400);
DISPLAY INVISIBLE (-1198 1400);
FORCEADD TAP..1
R 2
(-1200 1450);
FORCEPROP 3 LASTPIN (-1150 1450) SIG_NAME M_G_CPU1_SB_DQ<19>
J 0
(-1140 1460);
DISPLAY 0.659574 (-1140 1460);
PAINT MONO (-1140 1460);
DISPLAY INVISIBLE (-1140 1460);
FORCEPROP 1 LASTPIN (-1150 1450) BN 19
J 2
(-1138 1458);
DISPLAY 0.680851 (-1138 1458);
PAINT GREEN (-1138 1458);
FORCEPROP 2 LAST CDS_LIB standard
J 0
(-1200 1450);
DISPLAY INVISIBLE (-1200 1450);
FORCEPROP 1 LAST BODY_TYPE PLUMBING
J 2
(-1200 1500);
DISPLAY 0.872340 (-1200 1500);
PAINT GREEN (-1200 1500);
DISPLAY INVISIBLE (-1200 1500);
FORCEPROP 1 LAST HDL_TAP TRUE
J 2
(-1525 1325);
DISPLAY 0.872340 (-1525 1325);
DISPLAY INVISIBLE (-1525 1325);
FORCEPROP 1 LAST PATH I36
J 2
(-1198 1450);
DISPLAY 0.872340 (-1198 1450);
PAINT GREEN (-1198 1450);
DISPLAY INVISIBLE (-1198 1450);
FORCEADD TAP..1
R 2
(-1200 1500);
FORCEPROP 3 LASTPIN (-1150 1500) SIG_NAME M_G_CPU1_SB_DQ<20>
J 0
(-1140 1510);
DISPLAY 0.659574 (-1140 1510);
PAINT MONO (-1140 1510);
DISPLAY INVISIBLE (-1140 1510);
FORCEPROP 1 LASTPIN (-1150 1500) BN 20
J 2
(-1138 1508);
DISPLAY 0.680851 (-1138 1508);
PAINT GREEN (-1138 1508);
FORCEPROP 2 LAST CDS_LIB standard
J 0
(-1200 1500);
DISPLAY INVISIBLE (-1200 1500);
FORCEPROP 1 LAST BODY_TYPE PLUMBING
J 2
(-1200 1550);
DISPLAY 0.872340 (-1200 1550);
PAINT GREEN (-1200 1550);
DISPLAY INVISIBLE (-1200 1550);
FORCEPROP 1 LAST HDL_TAP TRUE
J 2
(-1525 1375);
DISPLAY 0.872340 (-1525 1375);
DISPLAY INVISIBLE (-1525 1375);
FORCEPROP 1 LAST PATH I37
J 2
(-1198 1500);
DISPLAY 0.872340 (-1198 1500);
PAINT GREEN (-1198 1500);
DISPLAY INVISIBLE (-1198 1500);
FORCEADD TAP..1
R 2
(-1200 1550);
FORCEPROP 3 LASTPIN (-1150 1550) SIG_NAME M_G_CPU1_SB_DQ<21>
J 0
(-1140 1560);
DISPLAY 0.659574 (-1140 1560);
PAINT MONO (-1140 1560);
DISPLAY INVISIBLE (-1140 1560);
FORCEPROP 1 LASTPIN (-1150 1550) BN 21
J 2
(-1138 1558);
DISPLAY 0.680851 (-1138 1558);
PAINT GREEN (-1138 1558);
FORCEPROP 2 LAST CDS_LIB standard
J 0
(-1200 1550);
DISPLAY INVISIBLE (-1200 1550);
FORCEPROP 1 LAST BODY_TYPE PLUMBING
J 2
(-1200 1600);
DISPLAY 0.872340 (-1200 1600);
PAINT GREEN (-1200 1600);
DISPLAY INVISIBLE (-1200 1600);
FORCEPROP 1 LAST HDL_TAP TRUE
J 2
(-1525 1425);
DISPLAY 0.872340 (-1525 1425);
DISPLAY INVISIBLE (-1525 1425);
FORCEPROP 1 LAST PATH I38
J 2
(-1198 1550);
DISPLAY 0.872340 (-1198 1550);
PAINT GREEN (-1198 1550);
DISPLAY INVISIBLE (-1198 1550);
FORCEADD TAP..1
R 2
(-1200 1600);
FORCEPROP 3 LASTPIN (-1150 1600) SIG_NAME M_G_CPU1_SB_DQ<22>
J 0
(-1140 1610);
DISPLAY 0.659574 (-1140 1610);
PAINT MONO (-1140 1610);
DISPLAY INVISIBLE (-1140 1610);
FORCEPROP 1 LASTPIN (-1150 1600) BN 22
J 2
(-1138 1608);
DISPLAY 0.680851 (-1138 1608);
PAINT GREEN (-1138 1608);
FORCEPROP 2 LAST CDS_LIB standard
J 0
(-1200 1600);
DISPLAY INVISIBLE (-1200 1600);
FORCEPROP 1 LAST BODY_TYPE PLUMBING
J 2
(-1200 1650);
DISPLAY 0.872340 (-1200 1650);
PAINT GREEN (-1200 1650);
DISPLAY INVISIBLE (-1200 1650);
FORCEPROP 1 LAST HDL_TAP TRUE
J 2
(-1525 1475);
DISPLAY 0.872340 (-1525 1475);
DISPLAY INVISIBLE (-1525 1475);
FORCEPROP 1 LAST PATH I39
J 2
(-1198 1600);
DISPLAY 0.872340 (-1198 1600);
PAINT GREEN (-1198 1600);
DISPLAY INVISIBLE (-1198 1600);
FORCEADD TAP..1
R 2
(-1200 -100);
FORCEPROP 3 LASTPIN (-1150 -100) SIG_NAME M_G_CPU1_CLK_DN<1>
J 0
(-1140 -90);
DISPLAY 0.659574 (-1140 -90);
PAINT MONO (-1140 -90);
DISPLAY INVISIBLE (-1140 -90);
FORCEPROP 1 LASTPIN (-1150 -100) BN 1
J 2
(-1138 -92);
DISPLAY 0.680851 (-1138 -92);
PAINT GREEN (-1138 -92);
FORCEPROP 2 LAST CDS_LIB standard
J 0
(-1200 -100);
DISPLAY INVISIBLE (-1200 -100);
FORCEPROP 1 LAST BODY_TYPE PLUMBING
J 2
(-1200 -50);
DISPLAY 0.872340 (-1200 -50);
PAINT GREEN (-1200 -50);
DISPLAY INVISIBLE (-1200 -50);
FORCEPROP 1 LAST HDL_TAP TRUE
J 2
(-1525 -225);
DISPLAY 0.872340 (-1525 -225);
DISPLAY INVISIBLE (-1525 -225);
FORCEPROP 1 LAST PATH I4
J 2
(-1198 -100);
DISPLAY 0.872340 (-1198 -100);
PAINT GREEN (-1198 -100);
DISPLAY INVISIBLE (-1198 -100);
FORCEADD TAP..1
R 2
(-1200 1650);
FORCEPROP 3 LASTPIN (-1150 1650) SIG_NAME M_G_CPU1_SB_DQ<23>
J 0
(-1140 1660);
DISPLAY 0.659574 (-1140 1660);
PAINT MONO (-1140 1660);
DISPLAY INVISIBLE (-1140 1660);
FORCEPROP 1 LASTPIN (-1150 1650) BN 23
J 2
(-1138 1658);
DISPLAY 0.680851 (-1138 1658);
PAINT GREEN (-1138 1658);
FORCEPROP 2 LAST CDS_LIB standard
J 0
(-1200 1650);
DISPLAY INVISIBLE (-1200 1650);
FORCEPROP 1 LAST BODY_TYPE PLUMBING
J 2
(-1200 1700);
DISPLAY 0.872340 (-1200 1700);
PAINT GREEN (-1200 1700);
DISPLAY INVISIBLE (-1200 1700);
FORCEPROP 1 LAST HDL_TAP TRUE
J 2
(-1525 1525);
DISPLAY 0.872340 (-1525 1525);
DISPLAY INVISIBLE (-1525 1525);
FORCEPROP 1 LAST PATH I40
J 2
(-1198 1650);
DISPLAY 0.872340 (-1198 1650);
PAINT GREEN (-1198 1650);
DISPLAY INVISIBLE (-1198 1650);
FORCEADD TAP..1
R 2
(-1200 1700);
FORCEPROP 3 LASTPIN (-1150 1700) SIG_NAME M_G_CPU1_SB_DQ<24>
J 0
(-1140 1710);
DISPLAY 0.659574 (-1140 1710);
PAINT MONO (-1140 1710);
DISPLAY INVISIBLE (-1140 1710);
FORCEPROP 1 LASTPIN (-1150 1700) BN 24
J 2
(-1138 1708);
DISPLAY 0.680851 (-1138 1708);
PAINT GREEN (-1138 1708);
FORCEPROP 2 LAST CDS_LIB standard
J 0
(-1200 1700);
DISPLAY INVISIBLE (-1200 1700);
FORCEPROP 1 LAST BODY_TYPE PLUMBING
J 2
(-1200 1750);
DISPLAY 0.872340 (-1200 1750);
PAINT GREEN (-1200 1750);
DISPLAY INVISIBLE (-1200 1750);
FORCEPROP 1 LAST HDL_TAP TRUE
J 2
(-1525 1575);
DISPLAY 0.872340 (-1525 1575);
DISPLAY INVISIBLE (-1525 1575);
FORCEPROP 1 LAST PATH I41
J 2
(-1198 1700);
DISPLAY 0.872340 (-1198 1700);
PAINT GREEN (-1198 1700);
DISPLAY INVISIBLE (-1198 1700);
FORCEADD TAP..1
R 2
(-1200 1750);
FORCEPROP 3 LASTPIN (-1150 1750) SIG_NAME M_G_CPU1_SB_DQ<25>
J 0
(-1140 1760);
DISPLAY 0.659574 (-1140 1760);
PAINT MONO (-1140 1760);
DISPLAY INVISIBLE (-1140 1760);
FORCEPROP 1 LASTPIN (-1150 1750) BN 25
J 2
(-1138 1758);
DISPLAY 0.680851 (-1138 1758);
PAINT GREEN (-1138 1758);
FORCEPROP 2 LAST CDS_LIB standard
J 0
(-1200 1750);
DISPLAY INVISIBLE (-1200 1750);
FORCEPROP 1 LAST BODY_TYPE PLUMBING
J 2
(-1200 1800);
DISPLAY 0.872340 (-1200 1800);
PAINT GREEN (-1200 1800);
DISPLAY INVISIBLE (-1200 1800);
FORCEPROP 1 LAST HDL_TAP TRUE
J 2
(-1525 1625);
DISPLAY 0.872340 (-1525 1625);
DISPLAY INVISIBLE (-1525 1625);
FORCEPROP 1 LAST PATH I42
J 2
(-1198 1750);
DISPLAY 0.872340 (-1198 1750);
PAINT GREEN (-1198 1750);
DISPLAY INVISIBLE (-1198 1750);
FORCEADD TAP..1
R 2
(-1200 1850);
FORCEPROP 3 LASTPIN (-1150 1850) SIG_NAME M_G_CPU1_SB_DQ<27>
J 0
(-1140 1860);
DISPLAY 0.659574 (-1140 1860);
PAINT MONO (-1140 1860);
DISPLAY INVISIBLE (-1140 1860);
FORCEPROP 1 LASTPIN (-1150 1850) BN 27
J 2
(-1138 1858);
DISPLAY 0.680851 (-1138 1858);
PAINT GREEN (-1138 1858);
FORCEPROP 2 LAST CDS_LIB standard
J 0
(-1200 1850);
DISPLAY INVISIBLE (-1200 1850);
FORCEPROP 1 LAST BODY_TYPE PLUMBING
J 2
(-1200 1900);
DISPLAY 0.872340 (-1200 1900);
PAINT GREEN (-1200 1900);
DISPLAY INVISIBLE (-1200 1900);
FORCEPROP 1 LAST HDL_TAP TRUE
J 2
(-1525 1725);
DISPLAY 0.872340 (-1525 1725);
DISPLAY INVISIBLE (-1525 1725);
FORCEPROP 1 LAST PATH I43
J 2
(-1198 1850);
DISPLAY 0.872340 (-1198 1850);
PAINT GREEN (-1198 1850);
DISPLAY INVISIBLE (-1198 1850);
FORCEADD TAP..1
R 2
(-1200 1800);
FORCEPROP 3 LASTPIN (-1150 1800) SIG_NAME M_G_CPU1_SB_DQ<26>
J 0
(-1140 1810);
DISPLAY 0.659574 (-1140 1810);
PAINT MONO (-1140 1810);
DISPLAY INVISIBLE (-1140 1810);
FORCEPROP 1 LASTPIN (-1150 1800) BN 26
J 2
(-1138 1808);
DISPLAY 0.680851 (-1138 1808);
PAINT GREEN (-1138 1808);
FORCEPROP 2 LAST CDS_LIB standard
J 0
(-1200 1800);
DISPLAY INVISIBLE (-1200 1800);
FORCEPROP 1 LAST BODY_TYPE PLUMBING
J 2
(-1200 1850);
DISPLAY 0.872340 (-1200 1850);
PAINT GREEN (-1200 1850);
DISPLAY INVISIBLE (-1200 1850);
FORCEPROP 1 LAST HDL_TAP TRUE
J 2
(-1525 1675);
DISPLAY 0.872340 (-1525 1675);
DISPLAY INVISIBLE (-1525 1675);
FORCEPROP 1 LAST PATH I44
J 2
(-1198 1800);
DISPLAY 0.872340 (-1198 1800);
PAINT GREEN (-1198 1800);
DISPLAY INVISIBLE (-1198 1800);
FORCEADD TAP..1
R 2
(-1200 1900);
FORCEPROP 3 LASTPIN (-1150 1900) SIG_NAME M_G_CPU1_SB_DQ<28>
J 0
(-1140 1910);
DISPLAY 0.659574 (-1140 1910);
PAINT MONO (-1140 1910);
DISPLAY INVISIBLE (-1140 1910);
FORCEPROP 1 LASTPIN (-1150 1900) BN 28
J 2
(-1138 1908);
DISPLAY 0.680851 (-1138 1908);
PAINT GREEN (-1138 1908);
FORCEPROP 2 LAST CDS_LIB standard
J 0
(-1200 1900);
DISPLAY INVISIBLE (-1200 1900);
FORCEPROP 1 LAST BODY_TYPE PLUMBING
J 2
(-1200 1950);
DISPLAY 0.872340 (-1200 1950);
PAINT GREEN (-1200 1950);
DISPLAY INVISIBLE (-1200 1950);
FORCEPROP 1 LAST HDL_TAP TRUE
J 2
(-1525 1775);
DISPLAY 0.872340 (-1525 1775);
DISPLAY INVISIBLE (-1525 1775);
FORCEPROP 1 LAST PATH I45
J 2
(-1198 1900);
DISPLAY 0.872340 (-1198 1900);
PAINT GREEN (-1198 1900);
DISPLAY INVISIBLE (-1198 1900);
FORCEADD TAP..1
R 2
(-1200 1950);
FORCEPROP 3 LASTPIN (-1150 1950) SIG_NAME M_G_CPU1_SB_DQ<29>
J 0
(-1140 1960);
DISPLAY 0.659574 (-1140 1960);
PAINT MONO (-1140 1960);
DISPLAY INVISIBLE (-1140 1960);
FORCEPROP 1 LASTPIN (-1150 1950) BN 29
J 2
(-1138 1958);
DISPLAY 0.680851 (-1138 1958);
PAINT GREEN (-1138 1958);
FORCEPROP 2 LAST CDS_LIB standard
J 0
(-1200 1950);
DISPLAY INVISIBLE (-1200 1950);
FORCEPROP 1 LAST BODY_TYPE PLUMBING
J 2
(-1200 2000);
DISPLAY 0.872340 (-1200 2000);
PAINT GREEN (-1200 2000);
DISPLAY INVISIBLE (-1200 2000);
FORCEPROP 1 LAST HDL_TAP TRUE
J 2
(-1525 1825);
DISPLAY 0.872340 (-1525 1825);
DISPLAY INVISIBLE (-1525 1825);
FORCEPROP 1 LAST PATH I46
J 2
(-1198 1950);
DISPLAY 0.872340 (-1198 1950);
PAINT GREEN (-1198 1950);
DISPLAY INVISIBLE (-1198 1950);
FORCEADD TAP..1
R 2
(-1200 2000);
FORCEPROP 3 LASTPIN (-1150 2000) SIG_NAME M_G_CPU1_SB_DQ<30>
J 0
(-1140 2010);
DISPLAY 0.659574 (-1140 2010);
PAINT MONO (-1140 2010);
DISPLAY INVISIBLE (-1140 2010);
FORCEPROP 1 LASTPIN (-1150 2000) BN 30
J 2
(-1138 2008);
DISPLAY 0.680851 (-1138 2008);
PAINT GREEN (-1138 2008);
FORCEPROP 2 LAST CDS_LIB standard
J 0
(-1200 2000);
DISPLAY INVISIBLE (-1200 2000);
FORCEPROP 1 LAST BODY_TYPE PLUMBING
J 2
(-1200 2050);
DISPLAY 0.872340 (-1200 2050);
PAINT GREEN (-1200 2050);
DISPLAY INVISIBLE (-1200 2050);
FORCEPROP 1 LAST HDL_TAP TRUE
J 2
(-1525 1875);
DISPLAY 0.872340 (-1525 1875);
DISPLAY INVISIBLE (-1525 1875);
FORCEPROP 1 LAST PATH I47
J 2
(-1198 2000);
DISPLAY 0.872340 (-1198 2000);
PAINT GREEN (-1198 2000);
DISPLAY INVISIBLE (-1198 2000);
FORCEADD OFFPAGE..3
R 2
(-2225 2475);
FORCEPROP 2 LAST $XR1 111 
J 0
(-2655 2475);
DISPLAY 0.638298 (-2655 2475);
PAINT MONO (-2655 2475);
FORCEPROP 2 LAST $XR0 110 
J 0
(-2535 2475);
DISPLAY 0.638298 (-2535 2475);
PAINT MONO (-2535 2475);
FORCEPROP 2 LAST CDS_LIB standard
J 0
(-2225 2475);
DISPLAY INVISIBLE (-2225 2475);
FORCEPROP 1 LAST OFFPAGE TRUE
J 2
(-2550 2350);
DISPLAY 0.872340 (-2550 2350);
DISPLAY INVISIBLE (-2550 2350);
FORCEPROP 1 LAST COMMENT_BODY TRUE
J 2
(-2175 2375);
DISPLAY 0.872340 (-2175 2375);
PAINT GREEN (-2175 2375);
DISPLAY INVISIBLE (-2175 2375);
FORCEPROP 2 LAST PATH I48
J 0
(-2175 2550);
DISPLAY 1.021277 (-2175 2550);
DISPLAY INVISIBLE (-2175 2550);
FORCEADD OFFPAGE..3
R 2
(-2225 4075);
FORCEPROP 2 LAST $XR1 111 
J 0
(-2655 4075);
DISPLAY 0.638298 (-2655 4075);
PAINT MONO (-2655 4075);
FORCEPROP 2 LAST $XR0 110 
J 0
(-2535 4075);
DISPLAY 0.638298 (-2535 4075);
PAINT MONO (-2535 4075);
FORCEPROP 2 LAST CDS_LIB standard
J 0
(-2225 4075);
DISPLAY INVISIBLE (-2225 4075);
FORCEPROP 1 LAST OFFPAGE TRUE
J 2
(-2550 3950);
DISPLAY 0.872340 (-2550 3950);
DISPLAY INVISIBLE (-2550 3950);
FORCEPROP 1 LAST COMMENT_BODY TRUE
J 2
(-2175 3975);
DISPLAY 0.872340 (-2175 3975);
PAINT GREEN (-2175 3975);
DISPLAY INVISIBLE (-2175 3975);
FORCEPROP 2 LAST PATH I49
J 0
(-2175 4150);
DISPLAY 1.021277 (-2175 4150);
DISPLAY INVISIBLE (-2175 4150);
FORCEADD TAP..1
R 2
(-1200 -50);
FORCEPROP 3 LASTPIN (-1150 -50) SIG_NAME M_G_CPU1_CLK_DP<0>
J 0
(-1140 -40);
DISPLAY 0.659574 (-1140 -40);
PAINT MONO (-1140 -40);
DISPLAY INVISIBLE (-1140 -40);
FORCEPROP 1 LASTPIN (-1150 -50) BN 0
J 2
(-1138 -42);
DISPLAY 0.680851 (-1138 -42);
PAINT GREEN (-1138 -42);
FORCEPROP 2 LAST CDS_LIB standard
J 0
(-1200 -50);
DISPLAY INVISIBLE (-1200 -50);
FORCEPROP 1 LAST BODY_TYPE PLUMBING
J 2
(-1200 0);
DISPLAY 0.872340 (-1200 0);
PAINT GREEN (-1200 0);
DISPLAY INVISIBLE (-1200 0);
FORCEPROP 1 LAST HDL_TAP TRUE
J 2
(-1525 -175);
DISPLAY 0.872340 (-1525 -175);
DISPLAY INVISIBLE (-1525 -175);
FORCEPROP 1 LAST PATH I5
J 2
(-1198 -50);
DISPLAY 0.872340 (-1198 -50);
PAINT GREEN (-1198 -50);
DISPLAY INVISIBLE (-1198 -50);
FORCEADD TAP..1
R 2
(-1200 2100);
FORCEPROP 3 LASTPIN (-1150 2100) SIG_NAME M_G_CPU1_SA_CB<0>
J 0
(-1140 2110);
DISPLAY 0.659574 (-1140 2110);
PAINT MONO (-1140 2110);
DISPLAY INVISIBLE (-1140 2110);
FORCEPROP 1 LASTPIN (-1150 2100) BN 0
J 2
(-1138 2108);
DISPLAY 0.680851 (-1138 2108);
PAINT GREEN (-1138 2108);
FORCEPROP 2 LAST CDS_LIB standard
J 0
(-1200 2100);
DISPLAY INVISIBLE (-1200 2100);
FORCEPROP 1 LAST BODY_TYPE PLUMBING
J 2
(-1200 2150);
DISPLAY 0.872340 (-1200 2150);
PAINT GREEN (-1200 2150);
DISPLAY INVISIBLE (-1200 2150);
FORCEPROP 1 LAST HDL_TAP TRUE
J 2
(-1525 1975);
DISPLAY 0.872340 (-1525 1975);
DISPLAY INVISIBLE (-1525 1975);
FORCEPROP 1 LAST PATH I50
J 2
(-1198 2100);
DISPLAY 0.872340 (-1198 2100);
PAINT GREEN (-1198 2100);
DISPLAY INVISIBLE (-1198 2100);
FORCEADD TAP..1
R 2
(-1200 2050);
FORCEPROP 3 LASTPIN (-1150 2050) SIG_NAME M_G_CPU1_SB_DQ<31>
J 0
(-1140 2060);
DISPLAY 0.659574 (-1140 2060);
PAINT MONO (-1140 2060);
DISPLAY INVISIBLE (-1140 2060);
FORCEPROP 1 LASTPIN (-1150 2050) BN 31
J 2
(-1138 2058);
DISPLAY 0.680851 (-1138 2058);
PAINT GREEN (-1138 2058);
FORCEPROP 2 LAST CDS_LIB standard
J 0
(-1200 2050);
DISPLAY INVISIBLE (-1200 2050);
FORCEPROP 1 LAST BODY_TYPE PLUMBING
J 2
(-1200 2100);
DISPLAY 0.872340 (-1200 2100);
PAINT GREEN (-1200 2100);
DISPLAY INVISIBLE (-1200 2100);
FORCEPROP 1 LAST HDL_TAP TRUE
J 2
(-1525 1925);
DISPLAY 0.872340 (-1525 1925);
DISPLAY INVISIBLE (-1525 1925);
FORCEPROP 1 LAST PATH I51
J 2
(-1198 2050);
DISPLAY 0.872340 (-1198 2050);
PAINT GREEN (-1198 2050);
DISPLAY INVISIBLE (-1198 2050);
FORCEADD TAP..1
R 2
(-1200 2150);
FORCEPROP 3 LASTPIN (-1150 2150) SIG_NAME M_G_CPU1_SA_CB<1>
J 0
(-1140 2160);
DISPLAY 0.659574 (-1140 2160);
PAINT MONO (-1140 2160);
DISPLAY INVISIBLE (-1140 2160);
FORCEPROP 1 LASTPIN (-1150 2150) BN 1
J 2
(-1138 2158);
DISPLAY 0.680851 (-1138 2158);
PAINT GREEN (-1138 2158);
FORCEPROP 2 LAST CDS_LIB standard
J 0
(-1200 2150);
DISPLAY INVISIBLE (-1200 2150);
FORCEPROP 1 LAST BODY_TYPE PLUMBING
J 2
(-1200 2200);
DISPLAY 0.872340 (-1200 2200);
PAINT GREEN (-1200 2200);
DISPLAY INVISIBLE (-1200 2200);
FORCEPROP 1 LAST HDL_TAP TRUE
J 2
(-1525 2025);
DISPLAY 0.872340 (-1525 2025);
DISPLAY INVISIBLE (-1525 2025);
FORCEPROP 1 LAST PATH I52
J 2
(-1198 2150);
DISPLAY 0.872340 (-1198 2150);
PAINT GREEN (-1198 2150);
DISPLAY INVISIBLE (-1198 2150);
FORCEADD TAP..1
R 2
(-1200 2200);
FORCEPROP 3 LASTPIN (-1150 2200) SIG_NAME M_G_CPU1_SA_CB<2>
J 0
(-1140 2210);
DISPLAY 0.659574 (-1140 2210);
PAINT MONO (-1140 2210);
DISPLAY INVISIBLE (-1140 2210);
FORCEPROP 1 LASTPIN (-1150 2200) BN 2
J 2
(-1138 2208);
DISPLAY 0.680851 (-1138 2208);
PAINT GREEN (-1138 2208);
FORCEPROP 2 LAST CDS_LIB standard
J 0
(-1200 2200);
DISPLAY INVISIBLE (-1200 2200);
FORCEPROP 1 LAST BODY_TYPE PLUMBING
J 2
(-1200 2250);
DISPLAY 0.872340 (-1200 2250);
PAINT GREEN (-1200 2250);
DISPLAY INVISIBLE (-1200 2250);
FORCEPROP 1 LAST HDL_TAP TRUE
J 2
(-1525 2075);
DISPLAY 0.872340 (-1525 2075);
DISPLAY INVISIBLE (-1525 2075);
FORCEPROP 1 LAST PATH I53
J 2
(-1198 2200);
DISPLAY 0.872340 (-1198 2200);
PAINT GREEN (-1198 2200);
DISPLAY INVISIBLE (-1198 2200);
FORCEADD TAP..1
R 2
(-1200 2250);
FORCEPROP 3 LASTPIN (-1150 2250) SIG_NAME M_G_CPU1_SA_CB<3>
J 0
(-1140 2260);
DISPLAY 0.659574 (-1140 2260);
PAINT MONO (-1140 2260);
DISPLAY INVISIBLE (-1140 2260);
FORCEPROP 1 LASTPIN (-1150 2250) BN 3
J 2
(-1138 2258);
DISPLAY 0.680851 (-1138 2258);
PAINT GREEN (-1138 2258);
FORCEPROP 2 LAST CDS_LIB standard
J 0
(-1200 2250);
DISPLAY INVISIBLE (-1200 2250);
FORCEPROP 1 LAST BODY_TYPE PLUMBING
J 2
(-1200 2300);
DISPLAY 0.872340 (-1200 2300);
PAINT GREEN (-1200 2300);
DISPLAY INVISIBLE (-1200 2300);
FORCEPROP 1 LAST HDL_TAP TRUE
J 2
(-1525 2125);
DISPLAY 0.872340 (-1525 2125);
DISPLAY INVISIBLE (-1525 2125);
FORCEPROP 1 LAST PATH I54
J 2
(-1198 2250);
DISPLAY 0.872340 (-1198 2250);
PAINT GREEN (-1198 2250);
DISPLAY INVISIBLE (-1198 2250);
FORCEADD TAP..1
R 2
(-1200 2300);
FORCEPROP 3 LASTPIN (-1150 2300) SIG_NAME M_G_CPU1_SA_CB<4>
J 0
(-1140 2310);
DISPLAY 0.659574 (-1140 2310);
PAINT MONO (-1140 2310);
DISPLAY INVISIBLE (-1140 2310);
FORCEPROP 1 LASTPIN (-1150 2300) BN 4
J 2
(-1138 2308);
DISPLAY 0.680851 (-1138 2308);
PAINT GREEN (-1138 2308);
FORCEPROP 2 LAST CDS_LIB standard
J 0
(-1200 2300);
DISPLAY INVISIBLE (-1200 2300);
FORCEPROP 1 LAST BODY_TYPE PLUMBING
J 2
(-1200 2350);
DISPLAY 0.872340 (-1200 2350);
PAINT GREEN (-1200 2350);
DISPLAY INVISIBLE (-1200 2350);
FORCEPROP 1 LAST HDL_TAP TRUE
J 2
(-1525 2175);
DISPLAY 0.872340 (-1525 2175);
DISPLAY INVISIBLE (-1525 2175);
FORCEPROP 1 LAST PATH I55
J 2
(-1198 2300);
DISPLAY 0.872340 (-1198 2300);
PAINT GREEN (-1198 2300);
DISPLAY INVISIBLE (-1198 2300);
FORCEADD TAP..1
R 2
(-1200 2350);
FORCEPROP 3 LASTPIN (-1150 2350) SIG_NAME M_G_CPU1_SA_CB<5>
J 0
(-1140 2360);
DISPLAY 0.659574 (-1140 2360);
PAINT MONO (-1140 2360);
DISPLAY INVISIBLE (-1140 2360);
FORCEPROP 1 LASTPIN (-1150 2350) BN 5
J 2
(-1138 2358);
DISPLAY 0.680851 (-1138 2358);
PAINT GREEN (-1138 2358);
FORCEPROP 2 LAST CDS_LIB standard
J 0
(-1200 2350);
DISPLAY INVISIBLE (-1200 2350);
FORCEPROP 1 LAST BODY_TYPE PLUMBING
J 2
(-1200 2400);
DISPLAY 0.872340 (-1200 2400);
PAINT GREEN (-1200 2400);
DISPLAY INVISIBLE (-1200 2400);
FORCEPROP 1 LAST HDL_TAP TRUE
J 2
(-1525 2225);
DISPLAY 0.872340 (-1525 2225);
DISPLAY INVISIBLE (-1525 2225);
FORCEPROP 1 LAST PATH I56
J 2
(-1198 2350);
DISPLAY 0.872340 (-1198 2350);
PAINT GREEN (-1198 2350);
DISPLAY INVISIBLE (-1198 2350);
FORCEADD TAP..1
R 2
(-1200 2400);
FORCEPROP 3 LASTPIN (-1150 2400) SIG_NAME M_G_CPU1_SA_CB<6>
J 0
(-1140 2410);
DISPLAY 0.659574 (-1140 2410);
PAINT MONO (-1140 2410);
DISPLAY INVISIBLE (-1140 2410);
FORCEPROP 1 LASTPIN (-1150 2400) BN 6
J 2
(-1138 2408);
DISPLAY 0.680851 (-1138 2408);
PAINT GREEN (-1138 2408);
FORCEPROP 2 LAST CDS_LIB standard
J 0
(-1200 2400);
DISPLAY INVISIBLE (-1200 2400);
FORCEPROP 1 LAST BODY_TYPE PLUMBING
J 2
(-1200 2450);
DISPLAY 0.872340 (-1200 2450);
PAINT GREEN (-1200 2450);
DISPLAY INVISIBLE (-1200 2450);
FORCEPROP 1 LAST HDL_TAP TRUE
J 2
(-1525 2275);
DISPLAY 0.872340 (-1525 2275);
DISPLAY INVISIBLE (-1525 2275);
FORCEPROP 1 LAST PATH I57
J 2
(-1198 2400);
DISPLAY 0.872340 (-1198 2400);
PAINT GREEN (-1198 2400);
DISPLAY INVISIBLE (-1198 2400);
FORCEADD TAP..1
R 2
(-1200 2450);
FORCEPROP 3 LASTPIN (-1150 2450) SIG_NAME M_G_CPU1_SA_CB<7>
J 0
(-1140 2460);
DISPLAY 0.659574 (-1140 2460);
PAINT MONO (-1140 2460);
DISPLAY INVISIBLE (-1140 2460);
FORCEPROP 1 LASTPIN (-1150 2450) BN 7
J 2
(-1138 2458);
DISPLAY 0.680851 (-1138 2458);
PAINT GREEN (-1138 2458);
FORCEPROP 2 LAST CDS_LIB standard
J 0
(-1200 2450);
DISPLAY INVISIBLE (-1200 2450);
FORCEPROP 1 LAST BODY_TYPE PLUMBING
J 2
(-1200 2500);
DISPLAY 0.872340 (-1200 2500);
PAINT GREEN (-1200 2500);
DISPLAY INVISIBLE (-1200 2500);
FORCEPROP 1 LAST HDL_TAP TRUE
J 2
(-1525 2325);
DISPLAY 0.872340 (-1525 2325);
DISPLAY INVISIBLE (-1525 2325);
FORCEPROP 1 LAST PATH I58
J 2
(-1198 2450);
DISPLAY 0.872340 (-1198 2450);
PAINT GREEN (-1198 2450);
DISPLAY INVISIBLE (-1198 2450);
FORCEADD TAP..1
R 2
(-1200 2550);
FORCEPROP 3 LASTPIN (-1150 2550) SIG_NAME M_G_CPU1_SA_DQ<1>
J 0
(-1140 2560);
DISPLAY 0.659574 (-1140 2560);
PAINT MONO (-1140 2560);
DISPLAY INVISIBLE (-1140 2560);
FORCEPROP 1 LASTPIN (-1150 2550) BN 1
J 2
(-1138 2558);
DISPLAY 0.680851 (-1138 2558);
PAINT GREEN (-1138 2558);
FORCEPROP 2 LAST CDS_LIB standard
J 0
(-1200 2550);
DISPLAY INVISIBLE (-1200 2550);
FORCEPROP 1 LAST BODY_TYPE PLUMBING
J 2
(-1200 2600);
DISPLAY 0.872340 (-1200 2600);
PAINT GREEN (-1200 2600);
DISPLAY INVISIBLE (-1200 2600);
FORCEPROP 1 LAST HDL_TAP TRUE
J 2
(-1525 2425);
DISPLAY 0.872340 (-1525 2425);
DISPLAY INVISIBLE (-1525 2425);
FORCEPROP 1 LAST PATH I59
J 2
(-1198 2550);
DISPLAY 0.872340 (-1198 2550);
PAINT GREEN (-1198 2550);
DISPLAY INVISIBLE (-1198 2550);
FORCEADD TAP..1
R 2
(-1200 0);
FORCEPROP 3 LASTPIN (-1150 0) SIG_NAME M_G_CPU1_CLK_DP<1>
J 0
(-1140 10);
DISPLAY 0.659574 (-1140 10);
PAINT MONO (-1140 10);
DISPLAY INVISIBLE (-1140 10);
FORCEPROP 1 LASTPIN (-1150 0) BN 1
J 2
(-1138 8);
DISPLAY 0.680851 (-1138 8);
PAINT GREEN (-1138 8);
FORCEPROP 2 LAST CDS_LIB standard
J 0
(-1200 0);
DISPLAY INVISIBLE (-1200 0);
FORCEPROP 1 LAST BODY_TYPE PLUMBING
J 2
(-1200 50);
DISPLAY 0.872340 (-1200 50);
PAINT GREEN (-1200 50);
DISPLAY INVISIBLE (-1200 50);
FORCEPROP 1 LAST HDL_TAP TRUE
J 2
(-1525 -125);
DISPLAY 0.872340 (-1525 -125);
DISPLAY INVISIBLE (-1525 -125);
FORCEPROP 1 LAST PATH I6
J 2
(-1198 0);
DISPLAY 0.872340 (-1198 0);
PAINT GREEN (-1198 0);
DISPLAY INVISIBLE (-1198 0);
FORCEADD TAP..1
R 2
(-1200 2500);
FORCEPROP 3 LASTPIN (-1150 2500) SIG_NAME M_G_CPU1_SA_DQ<0>
J 0
(-1140 2510);
DISPLAY 0.659574 (-1140 2510);
PAINT MONO (-1140 2510);
DISPLAY INVISIBLE (-1140 2510);
FORCEPROP 1 LASTPIN (-1150 2500) BN 0
J 2
(-1138 2508);
DISPLAY 0.680851 (-1138 2508);
PAINT GREEN (-1138 2508);
FORCEPROP 2 LAST CDS_LIB standard
J 0
(-1200 2500);
DISPLAY INVISIBLE (-1200 2500);
FORCEPROP 1 LAST BODY_TYPE PLUMBING
J 2
(-1200 2550);
DISPLAY 0.872340 (-1200 2550);
PAINT GREEN (-1200 2550);
DISPLAY INVISIBLE (-1200 2550);
FORCEPROP 1 LAST HDL_TAP TRUE
J 2
(-1525 2375);
DISPLAY 0.872340 (-1525 2375);
DISPLAY INVISIBLE (-1525 2375);
FORCEPROP 1 LAST PATH I60
J 2
(-1198 2500);
DISPLAY 0.872340 (-1198 2500);
PAINT GREEN (-1198 2500);
DISPLAY INVISIBLE (-1198 2500);
FORCEADD TAP..1
R 2
(-1200 2600);
FORCEPROP 3 LASTPIN (-1150 2600) SIG_NAME M_G_CPU1_SA_DQ<2>
J 0
(-1140 2610);
DISPLAY 0.659574 (-1140 2610);
PAINT MONO (-1140 2610);
DISPLAY INVISIBLE (-1140 2610);
FORCEPROP 1 LASTPIN (-1150 2600) BN 2
J 2
(-1138 2608);
DISPLAY 0.680851 (-1138 2608);
PAINT GREEN (-1138 2608);
FORCEPROP 2 LAST CDS_LIB standard
J 0
(-1200 2600);
DISPLAY INVISIBLE (-1200 2600);
FORCEPROP 1 LAST BODY_TYPE PLUMBING
J 2
(-1200 2650);
DISPLAY 0.872340 (-1200 2650);
PAINT GREEN (-1200 2650);
DISPLAY INVISIBLE (-1200 2650);
FORCEPROP 1 LAST HDL_TAP TRUE
J 2
(-1525 2475);
DISPLAY 0.872340 (-1525 2475);
DISPLAY INVISIBLE (-1525 2475);
FORCEPROP 1 LAST PATH I61
J 2
(-1198 2600);
DISPLAY 0.872340 (-1198 2600);
PAINT GREEN (-1198 2600);
DISPLAY INVISIBLE (-1198 2600);
FORCEADD TAP..1
R 2
(-1200 2650);
FORCEPROP 3 LASTPIN (-1150 2650) SIG_NAME M_G_CPU1_SA_DQ<3>
J 0
(-1140 2660);
DISPLAY 0.659574 (-1140 2660);
PAINT MONO (-1140 2660);
DISPLAY INVISIBLE (-1140 2660);
FORCEPROP 1 LASTPIN (-1150 2650) BN 3
J 2
(-1138 2658);
DISPLAY 0.680851 (-1138 2658);
PAINT GREEN (-1138 2658);
FORCEPROP 2 LAST CDS_LIB standard
J 0
(-1200 2650);
DISPLAY INVISIBLE (-1200 2650);
FORCEPROP 1 LAST BODY_TYPE PLUMBING
J 2
(-1200 2700);
DISPLAY 0.872340 (-1200 2700);
PAINT GREEN (-1200 2700);
DISPLAY INVISIBLE (-1200 2700);
FORCEPROP 1 LAST HDL_TAP TRUE
J 2
(-1525 2525);
DISPLAY 0.872340 (-1525 2525);
DISPLAY INVISIBLE (-1525 2525);
FORCEPROP 1 LAST PATH I62
J 2
(-1198 2650);
DISPLAY 0.872340 (-1198 2650);
PAINT GREEN (-1198 2650);
DISPLAY INVISIBLE (-1198 2650);
FORCEADD TAP..1
R 2
(-1200 2750);
FORCEPROP 3 LASTPIN (-1150 2750) SIG_NAME M_G_CPU1_SA_DQ<5>
J 0
(-1140 2760);
DISPLAY 0.659574 (-1140 2760);
PAINT MONO (-1140 2760);
DISPLAY INVISIBLE (-1140 2760);
FORCEPROP 1 LASTPIN (-1150 2750) BN 5
J 2
(-1138 2758);
DISPLAY 0.680851 (-1138 2758);
PAINT GREEN (-1138 2758);
FORCEPROP 2 LAST CDS_LIB standard
J 0
(-1200 2750);
DISPLAY INVISIBLE (-1200 2750);
FORCEPROP 1 LAST BODY_TYPE PLUMBING
J 2
(-1200 2800);
DISPLAY 0.872340 (-1200 2800);
PAINT GREEN (-1200 2800);
DISPLAY INVISIBLE (-1200 2800);
FORCEPROP 1 LAST HDL_TAP TRUE
J 2
(-1525 2625);
DISPLAY 0.872340 (-1525 2625);
DISPLAY INVISIBLE (-1525 2625);
FORCEPROP 1 LAST PATH I63
J 2
(-1198 2750);
DISPLAY 0.872340 (-1198 2750);
PAINT GREEN (-1198 2750);
DISPLAY INVISIBLE (-1198 2750);
FORCEADD TAP..1
R 2
(-1200 2700);
FORCEPROP 3 LASTPIN (-1150 2700) SIG_NAME M_G_CPU1_SA_DQ<4>
J 0
(-1140 2710);
DISPLAY 0.659574 (-1140 2710);
PAINT MONO (-1140 2710);
DISPLAY INVISIBLE (-1140 2710);
FORCEPROP 1 LASTPIN (-1150 2700) BN 4
J 2
(-1138 2708);
DISPLAY 0.680851 (-1138 2708);
PAINT GREEN (-1138 2708);
FORCEPROP 2 LAST CDS_LIB standard
J 0
(-1200 2700);
DISPLAY INVISIBLE (-1200 2700);
FORCEPROP 1 LAST BODY_TYPE PLUMBING
J 2
(-1200 2750);
DISPLAY 0.872340 (-1200 2750);
PAINT GREEN (-1200 2750);
DISPLAY INVISIBLE (-1200 2750);
FORCEPROP 1 LAST HDL_TAP TRUE
J 2
(-1525 2575);
DISPLAY 0.872340 (-1525 2575);
DISPLAY INVISIBLE (-1525 2575);
FORCEPROP 1 LAST PATH I64
J 2
(-1198 2700);
DISPLAY 0.872340 (-1198 2700);
PAINT GREEN (-1198 2700);
DISPLAY INVISIBLE (-1198 2700);
FORCEADD TAP..1
R 2
(-1200 2800);
FORCEPROP 3 LASTPIN (-1150 2800) SIG_NAME M_G_CPU1_SA_DQ<6>
J 0
(-1140 2810);
DISPLAY 0.659574 (-1140 2810);
PAINT MONO (-1140 2810);
DISPLAY INVISIBLE (-1140 2810);
FORCEPROP 1 LASTPIN (-1150 2800) BN 6
J 2
(-1138 2808);
DISPLAY 0.680851 (-1138 2808);
PAINT GREEN (-1138 2808);
FORCEPROP 2 LAST CDS_LIB standard
J 0
(-1200 2800);
DISPLAY INVISIBLE (-1200 2800);
FORCEPROP 1 LAST BODY_TYPE PLUMBING
J 2
(-1200 2850);
DISPLAY 0.872340 (-1200 2850);
PAINT GREEN (-1200 2850);
DISPLAY INVISIBLE (-1200 2850);
FORCEPROP 1 LAST HDL_TAP TRUE
J 2
(-1525 2675);
DISPLAY 0.872340 (-1525 2675);
DISPLAY INVISIBLE (-1525 2675);
FORCEPROP 1 LAST PATH I65
J 2
(-1198 2800);
DISPLAY 0.872340 (-1198 2800);
PAINT GREEN (-1198 2800);
DISPLAY INVISIBLE (-1198 2800);
FORCEADD TAP..1
R 2
(-1200 2850);
FORCEPROP 3 LASTPIN (-1150 2850) SIG_NAME M_G_CPU1_SA_DQ<7>
J 0
(-1140 2860);
DISPLAY 0.659574 (-1140 2860);
PAINT MONO (-1140 2860);
DISPLAY INVISIBLE (-1140 2860);
FORCEPROP 1 LASTPIN (-1150 2850) BN 7
J 2
(-1138 2858);
DISPLAY 0.680851 (-1138 2858);
PAINT GREEN (-1138 2858);
FORCEPROP 2 LAST CDS_LIB standard
J 0
(-1200 2850);
DISPLAY INVISIBLE (-1200 2850);
FORCEPROP 1 LAST BODY_TYPE PLUMBING
J 2
(-1200 2900);
DISPLAY 0.872340 (-1200 2900);
PAINT GREEN (-1200 2900);
DISPLAY INVISIBLE (-1200 2900);
FORCEPROP 1 LAST HDL_TAP TRUE
J 2
(-1525 2725);
DISPLAY 0.872340 (-1525 2725);
DISPLAY INVISIBLE (-1525 2725);
FORCEPROP 1 LAST PATH I66
J 2
(-1198 2850);
DISPLAY 0.872340 (-1198 2850);
PAINT GREEN (-1198 2850);
DISPLAY INVISIBLE (-1198 2850);
FORCEADD TAP..1
R 2
(-1200 2900);
FORCEPROP 3 LASTPIN (-1150 2900) SIG_NAME M_G_CPU1_SA_DQ<8>
J 0
(-1140 2910);
DISPLAY 0.659574 (-1140 2910);
PAINT MONO (-1140 2910);
DISPLAY INVISIBLE (-1140 2910);
FORCEPROP 1 LASTPIN (-1150 2900) BN 8
J 2
(-1138 2908);
DISPLAY 0.680851 (-1138 2908);
PAINT GREEN (-1138 2908);
FORCEPROP 2 LAST CDS_LIB standard
J 0
(-1200 2900);
DISPLAY INVISIBLE (-1200 2900);
FORCEPROP 1 LAST BODY_TYPE PLUMBING
J 2
(-1200 2950);
DISPLAY 0.872340 (-1200 2950);
PAINT GREEN (-1200 2950);
DISPLAY INVISIBLE (-1200 2950);
FORCEPROP 1 LAST HDL_TAP TRUE
J 2
(-1525 2775);
DISPLAY 0.872340 (-1525 2775);
DISPLAY INVISIBLE (-1525 2775);
FORCEPROP 1 LAST PATH I67
J 2
(-1198 2900);
DISPLAY 0.872340 (-1198 2900);
PAINT GREEN (-1198 2900);
DISPLAY INVISIBLE (-1198 2900);
FORCEADD TAP..1
R 2
(-1200 3000);
FORCEPROP 3 LASTPIN (-1150 3000) SIG_NAME M_G_CPU1_SA_DQ<10>
J 0
(-1140 3010);
DISPLAY 0.659574 (-1140 3010);
PAINT MONO (-1140 3010);
DISPLAY INVISIBLE (-1140 3010);
FORCEPROP 1 LASTPIN (-1150 3000) BN 10
J 2
(-1138 3008);
DISPLAY 0.680851 (-1138 3008);
PAINT GREEN (-1138 3008);
FORCEPROP 2 LAST CDS_LIB standard
J 0
(-1200 3000);
DISPLAY INVISIBLE (-1200 3000);
FORCEPROP 1 LAST BODY_TYPE PLUMBING
J 2
(-1200 3050);
DISPLAY 0.872340 (-1200 3050);
PAINT GREEN (-1200 3050);
DISPLAY INVISIBLE (-1200 3050);
FORCEPROP 1 LAST HDL_TAP TRUE
J 2
(-1525 2875);
DISPLAY 0.872340 (-1525 2875);
DISPLAY INVISIBLE (-1525 2875);
FORCEPROP 1 LAST PATH I68
J 2
(-1198 3000);
DISPLAY 0.872340 (-1198 3000);
PAINT GREEN (-1198 3000);
DISPLAY INVISIBLE (-1198 3000);
FORCEADD TAP..1
R 2
(-1200 2950);
FORCEPROP 3 LASTPIN (-1150 2950) SIG_NAME M_G_CPU1_SA_DQ<9>
J 0
(-1140 2960);
DISPLAY 0.659574 (-1140 2960);
PAINT MONO (-1140 2960);
DISPLAY INVISIBLE (-1140 2960);
FORCEPROP 1 LASTPIN (-1150 2950) BN 9
J 2
(-1138 2958);
DISPLAY 0.680851 (-1138 2958);
PAINT GREEN (-1138 2958);
FORCEPROP 2 LAST CDS_LIB standard
J 0
(-1200 2950);
DISPLAY INVISIBLE (-1200 2950);
FORCEPROP 1 LAST BODY_TYPE PLUMBING
J 2
(-1200 3000);
DISPLAY 0.872340 (-1200 3000);
PAINT GREEN (-1200 3000);
DISPLAY INVISIBLE (-1200 3000);
FORCEPROP 1 LAST HDL_TAP TRUE
J 2
(-1525 2825);
DISPLAY 0.872340 (-1525 2825);
DISPLAY INVISIBLE (-1525 2825);
FORCEPROP 1 LAST PATH I69
J 2
(-1198 2950);
DISPLAY 0.872340 (-1198 2950);
PAINT GREEN (-1198 2950);
DISPLAY INVISIBLE (-1198 2950);
FORCEADD OFFPAGE..3
R 2
(-2225 475);
FORCEPROP 2 LAST $XR1 111 
J 0
(-2655 475);
DISPLAY 0.638298 (-2655 475);
PAINT MONO (-2655 475);
FORCEPROP 2 LAST $XR0 110 
J 0
(-2535 475);
DISPLAY 0.638298 (-2535 475);
PAINT MONO (-2535 475);
FORCEPROP 2 LAST CDS_LIB standard
J 0
(-2225 475);
DISPLAY INVISIBLE (-2225 475);
FORCEPROP 1 LAST OFFPAGE TRUE
J 2
(-2550 350);
DISPLAY 0.872340 (-2550 350);
DISPLAY INVISIBLE (-2550 350);
FORCEPROP 1 LAST COMMENT_BODY TRUE
J 2
(-2175 375);
DISPLAY 0.872340 (-2175 375);
PAINT GREEN (-2175 375);
DISPLAY INVISIBLE (-2175 375);
FORCEPROP 2 LAST PATH I7
J 0
(-2175 550);
DISPLAY 1.021277 (-2175 550);
DISPLAY INVISIBLE (-2175 550);
FORCEADD TAP..1
R 2
(-1200 3050);
FORCEPROP 3 LASTPIN (-1150 3050) SIG_NAME M_G_CPU1_SA_DQ<11>
J 0
(-1140 3060);
DISPLAY 0.659574 (-1140 3060);
PAINT MONO (-1140 3060);
DISPLAY INVISIBLE (-1140 3060);
FORCEPROP 1 LASTPIN (-1150 3050) BN 11
J 2
(-1138 3058);
DISPLAY 0.680851 (-1138 3058);
PAINT GREEN (-1138 3058);
FORCEPROP 2 LAST CDS_LIB standard
J 0
(-1200 3050);
DISPLAY INVISIBLE (-1200 3050);
FORCEPROP 1 LAST BODY_TYPE PLUMBING
J 2
(-1200 3100);
DISPLAY 0.872340 (-1200 3100);
PAINT GREEN (-1200 3100);
DISPLAY INVISIBLE (-1200 3100);
FORCEPROP 1 LAST HDL_TAP TRUE
J 2
(-1525 2925);
DISPLAY 0.872340 (-1525 2925);
DISPLAY INVISIBLE (-1525 2925);
FORCEPROP 1 LAST PATH I70
J 2
(-1198 3050);
DISPLAY 0.872340 (-1198 3050);
PAINT GREEN (-1198 3050);
DISPLAY INVISIBLE (-1198 3050);
FORCEADD TAP..1
R 2
(-1200 3100);
FORCEPROP 3 LASTPIN (-1150 3100) SIG_NAME M_G_CPU1_SA_DQ<12>
J 0
(-1140 3110);
DISPLAY 0.659574 (-1140 3110);
PAINT MONO (-1140 3110);
DISPLAY INVISIBLE (-1140 3110);
FORCEPROP 1 LASTPIN (-1150 3100) BN 12
J 2
(-1138 3108);
DISPLAY 0.680851 (-1138 3108);
PAINT GREEN (-1138 3108);
FORCEPROP 2 LAST CDS_LIB standard
J 0
(-1200 3100);
DISPLAY INVISIBLE (-1200 3100);
FORCEPROP 1 LAST BODY_TYPE PLUMBING
J 2
(-1200 3150);
DISPLAY 0.872340 (-1200 3150);
PAINT GREEN (-1200 3150);
DISPLAY INVISIBLE (-1200 3150);
FORCEPROP 1 LAST HDL_TAP TRUE
J 2
(-1525 2975);
DISPLAY 0.872340 (-1525 2975);
DISPLAY INVISIBLE (-1525 2975);
FORCEPROP 1 LAST PATH I71
J 2
(-1198 3100);
DISPLAY 0.872340 (-1198 3100);
PAINT GREEN (-1198 3100);
DISPLAY INVISIBLE (-1198 3100);
FORCEADD TAP..1
R 2
(-1200 3150);
FORCEPROP 3 LASTPIN (-1150 3150) SIG_NAME M_G_CPU1_SA_DQ<13>
J 0
(-1140 3160);
DISPLAY 0.659574 (-1140 3160);
PAINT MONO (-1140 3160);
DISPLAY INVISIBLE (-1140 3160);
FORCEPROP 1 LASTPIN (-1150 3150) BN 13
J 2
(-1138 3158);
DISPLAY 0.680851 (-1138 3158);
PAINT GREEN (-1138 3158);
FORCEPROP 2 LAST CDS_LIB standard
J 0
(-1200 3150);
DISPLAY INVISIBLE (-1200 3150);
FORCEPROP 1 LAST BODY_TYPE PLUMBING
J 2
(-1200 3200);
DISPLAY 0.872340 (-1200 3200);
PAINT GREEN (-1200 3200);
DISPLAY INVISIBLE (-1200 3200);
FORCEPROP 1 LAST HDL_TAP TRUE
J 2
(-1525 3025);
DISPLAY 0.872340 (-1525 3025);
DISPLAY INVISIBLE (-1525 3025);
FORCEPROP 1 LAST PATH I72
J 2
(-1198 3150);
DISPLAY 0.872340 (-1198 3150);
PAINT GREEN (-1198 3150);
DISPLAY INVISIBLE (-1198 3150);
FORCEADD TAP..1
R 2
(-1200 3200);
FORCEPROP 3 LASTPIN (-1150 3200) SIG_NAME M_G_CPU1_SA_DQ<14>
J 0
(-1140 3210);
DISPLAY 0.659574 (-1140 3210);
PAINT MONO (-1140 3210);
DISPLAY INVISIBLE (-1140 3210);
FORCEPROP 1 LASTPIN (-1150 3200) BN 14
J 2
(-1138 3208);
DISPLAY 0.680851 (-1138 3208);
PAINT GREEN (-1138 3208);
FORCEPROP 2 LAST CDS_LIB standard
J 0
(-1200 3200);
DISPLAY INVISIBLE (-1200 3200);
FORCEPROP 1 LAST BODY_TYPE PLUMBING
J 2
(-1200 3250);
DISPLAY 0.872340 (-1200 3250);
PAINT GREEN (-1200 3250);
DISPLAY INVISIBLE (-1200 3250);
FORCEPROP 1 LAST HDL_TAP TRUE
J 2
(-1525 3075);
DISPLAY 0.872340 (-1525 3075);
DISPLAY INVISIBLE (-1525 3075);
FORCEPROP 1 LAST PATH I73
J 2
(-1198 3200);
DISPLAY 0.872340 (-1198 3200);
PAINT GREEN (-1198 3200);
DISPLAY INVISIBLE (-1198 3200);
FORCEADD TAP..1
R 2
(-1200 3250);
FORCEPROP 3 LASTPIN (-1150 3250) SIG_NAME M_G_CPU1_SA_DQ<15>
J 0
(-1140 3260);
DISPLAY 0.659574 (-1140 3260);
PAINT MONO (-1140 3260);
DISPLAY INVISIBLE (-1140 3260);
FORCEPROP 1 LASTPIN (-1150 3250) BN 15
J 2
(-1138 3258);
DISPLAY 0.680851 (-1138 3258);
PAINT GREEN (-1138 3258);
FORCEPROP 2 LAST CDS_LIB standard
J 0
(-1200 3250);
DISPLAY INVISIBLE (-1200 3250);
FORCEPROP 1 LAST BODY_TYPE PLUMBING
J 2
(-1200 3300);
DISPLAY 0.872340 (-1200 3300);
PAINT GREEN (-1200 3300);
DISPLAY INVISIBLE (-1200 3300);
FORCEPROP 1 LAST HDL_TAP TRUE
J 2
(-1525 3125);
DISPLAY 0.872340 (-1525 3125);
DISPLAY INVISIBLE (-1525 3125);
FORCEPROP 1 LAST PATH I74
J 2
(-1198 3250);
DISPLAY 0.872340 (-1198 3250);
PAINT GREEN (-1198 3250);
DISPLAY INVISIBLE (-1198 3250);
FORCEADD TAP..1
R 2
(-1200 3300);
FORCEPROP 3 LASTPIN (-1150 3300) SIG_NAME M_G_CPU1_SA_DQ<16>
J 0
(-1140 3310);
DISPLAY 0.659574 (-1140 3310);
PAINT MONO (-1140 3310);
DISPLAY INVISIBLE (-1140 3310);
FORCEPROP 1 LASTPIN (-1150 3300) BN 16
J 2
(-1138 3308);
DISPLAY 0.680851 (-1138 3308);
PAINT GREEN (-1138 3308);
FORCEPROP 2 LAST CDS_LIB standard
J 0
(-1200 3300);
DISPLAY INVISIBLE (-1200 3300);
FORCEPROP 1 LAST BODY_TYPE PLUMBING
J 2
(-1200 3350);
DISPLAY 0.872340 (-1200 3350);
PAINT GREEN (-1200 3350);
DISPLAY INVISIBLE (-1200 3350);
FORCEPROP 1 LAST HDL_TAP TRUE
J 2
(-1525 3175);
DISPLAY 0.872340 (-1525 3175);
DISPLAY INVISIBLE (-1525 3175);
FORCEPROP 1 LAST PATH I75
J 2
(-1198 3300);
DISPLAY 0.872340 (-1198 3300);
PAINT GREEN (-1198 3300);
DISPLAY INVISIBLE (-1198 3300);
FORCEADD TAP..1
R 2
(-1200 3350);
FORCEPROP 3 LASTPIN (-1150 3350) SIG_NAME M_G_CPU1_SA_DQ<17>
J 0
(-1140 3360);
DISPLAY 0.659574 (-1140 3360);
PAINT MONO (-1140 3360);
DISPLAY INVISIBLE (-1140 3360);
FORCEPROP 1 LASTPIN (-1150 3350) BN 17
J 2
(-1138 3358);
DISPLAY 0.680851 (-1138 3358);
PAINT GREEN (-1138 3358);
FORCEPROP 2 LAST CDS_LIB standard
J 0
(-1200 3350);
DISPLAY INVISIBLE (-1200 3350);
FORCEPROP 1 LAST BODY_TYPE PLUMBING
J 2
(-1200 3400);
DISPLAY 0.872340 (-1200 3400);
PAINT GREEN (-1200 3400);
DISPLAY INVISIBLE (-1200 3400);
FORCEPROP 1 LAST HDL_TAP TRUE
J 2
(-1525 3225);
DISPLAY 0.872340 (-1525 3225);
DISPLAY INVISIBLE (-1525 3225);
FORCEPROP 1 LAST PATH I76
J 2
(-1198 3350);
DISPLAY 0.872340 (-1198 3350);
PAINT GREEN (-1198 3350);
DISPLAY INVISIBLE (-1198 3350);
FORCEADD TAP..1
R 2
(-1200 3400);
FORCEPROP 3 LASTPIN (-1150 3400) SIG_NAME M_G_CPU1_SA_DQ<18>
J 0
(-1140 3410);
DISPLAY 0.659574 (-1140 3410);
PAINT MONO (-1140 3410);
DISPLAY INVISIBLE (-1140 3410);
FORCEPROP 1 LASTPIN (-1150 3400) BN 18
J 2
(-1138 3408);
DISPLAY 0.680851 (-1138 3408);
PAINT GREEN (-1138 3408);
FORCEPROP 2 LAST CDS_LIB standard
J 0
(-1200 3400);
DISPLAY INVISIBLE (-1200 3400);
FORCEPROP 1 LAST BODY_TYPE PLUMBING
J 2
(-1200 3450);
DISPLAY 0.872340 (-1200 3450);
PAINT GREEN (-1200 3450);
DISPLAY INVISIBLE (-1200 3450);
FORCEPROP 1 LAST HDL_TAP TRUE
J 2
(-1525 3275);
DISPLAY 0.872340 (-1525 3275);
DISPLAY INVISIBLE (-1525 3275);
FORCEPROP 1 LAST PATH I77
J 2
(-1198 3400);
DISPLAY 0.872340 (-1198 3400);
PAINT GREEN (-1198 3400);
DISPLAY INVISIBLE (-1198 3400);
FORCEADD TAP..1
R 2
(-1200 3450);
FORCEPROP 3 LASTPIN (-1150 3450) SIG_NAME M_G_CPU1_SA_DQ<19>
J 0
(-1140 3460);
DISPLAY 0.659574 (-1140 3460);
PAINT MONO (-1140 3460);
DISPLAY INVISIBLE (-1140 3460);
FORCEPROP 1 LASTPIN (-1150 3450) BN 19
J 2
(-1138 3458);
DISPLAY 0.680851 (-1138 3458);
PAINT GREEN (-1138 3458);
FORCEPROP 2 LAST CDS_LIB standard
J 0
(-1200 3450);
DISPLAY INVISIBLE (-1200 3450);
FORCEPROP 1 LAST BODY_TYPE PLUMBING
J 2
(-1200 3500);
DISPLAY 0.872340 (-1200 3500);
PAINT GREEN (-1200 3500);
DISPLAY INVISIBLE (-1200 3500);
FORCEPROP 1 LAST HDL_TAP TRUE
J 2
(-1525 3325);
DISPLAY 0.872340 (-1525 3325);
DISPLAY INVISIBLE (-1525 3325);
FORCEPROP 1 LAST PATH I78
J 2
(-1198 3450);
DISPLAY 0.872340 (-1198 3450);
PAINT GREEN (-1198 3450);
DISPLAY INVISIBLE (-1198 3450);
FORCEADD TAP..1
R 2
(-1200 3500);
FORCEPROP 3 LASTPIN (-1150 3500) SIG_NAME M_G_CPU1_SA_DQ<20>
J 0
(-1140 3510);
DISPLAY 0.659574 (-1140 3510);
PAINT MONO (-1140 3510);
DISPLAY INVISIBLE (-1140 3510);
FORCEPROP 1 LASTPIN (-1150 3500) BN 20
J 2
(-1138 3508);
DISPLAY 0.680851 (-1138 3508);
PAINT GREEN (-1138 3508);
FORCEPROP 2 LAST CDS_LIB standard
J 0
(-1200 3500);
DISPLAY INVISIBLE (-1200 3500);
FORCEPROP 1 LAST BODY_TYPE PLUMBING
J 2
(-1200 3550);
DISPLAY 0.872340 (-1200 3550);
PAINT GREEN (-1200 3550);
DISPLAY INVISIBLE (-1200 3550);
FORCEPROP 1 LAST HDL_TAP TRUE
J 2
(-1525 3375);
DISPLAY 0.872340 (-1525 3375);
DISPLAY INVISIBLE (-1525 3375);
FORCEPROP 1 LAST PATH I79
J 2
(-1198 3500);
DISPLAY 0.872340 (-1198 3500);
PAINT GREEN (-1198 3500);
DISPLAY INVISIBLE (-1198 3500);
FORCEADD OFFPAGE..3
R 2
(-2225 2075);
FORCEPROP 2 LAST $XR1 111 
J 0
(-2655 2075);
DISPLAY 0.638298 (-2655 2075);
PAINT MONO (-2655 2075);
FORCEPROP 2 LAST $XR0 110 
J 0
(-2535 2075);
DISPLAY 0.638298 (-2535 2075);
PAINT MONO (-2535 2075);
FORCEPROP 2 LAST CDS_LIB standard
J 0
(-2225 2075);
DISPLAY INVISIBLE (-2225 2075);
FORCEPROP 1 LAST OFFPAGE TRUE
J 2
(-2550 1950);
DISPLAY 0.872340 (-2550 1950);
DISPLAY INVISIBLE (-2550 1950);
FORCEPROP 1 LAST COMMENT_BODY TRUE
J 2
(-2175 1975);
DISPLAY 0.872340 (-2175 1975);
PAINT GREEN (-2175 1975);
DISPLAY INVISIBLE (-2175 1975);
FORCEPROP 2 LAST PATH I8
J 0
(-2175 2150);
DISPLAY 1.021277 (-2175 2150);
DISPLAY INVISIBLE (-2175 2150);
FORCEADD TAP..1
R 2
(-1200 3550);
FORCEPROP 3 LASTPIN (-1150 3550) SIG_NAME M_G_CPU1_SA_DQ<21>
J 0
(-1140 3560);
DISPLAY 0.659574 (-1140 3560);
PAINT MONO (-1140 3560);
DISPLAY INVISIBLE (-1140 3560);
FORCEPROP 1 LASTPIN (-1150 3550) BN 21
J 2
(-1138 3558);
DISPLAY 0.680851 (-1138 3558);
PAINT GREEN (-1138 3558);
FORCEPROP 2 LAST CDS_LIB standard
J 0
(-1200 3550);
DISPLAY INVISIBLE (-1200 3550);
FORCEPROP 1 LAST BODY_TYPE PLUMBING
J 2
(-1200 3600);
DISPLAY 0.872340 (-1200 3600);
PAINT GREEN (-1200 3600);
DISPLAY INVISIBLE (-1200 3600);
FORCEPROP 1 LAST HDL_TAP TRUE
J 2
(-1525 3425);
DISPLAY 0.872340 (-1525 3425);
DISPLAY INVISIBLE (-1525 3425);
FORCEPROP 1 LAST PATH I80
J 2
(-1198 3550);
DISPLAY 0.872340 (-1198 3550);
PAINT GREEN (-1198 3550);
DISPLAY INVISIBLE (-1198 3550);
FORCEADD TAP..1
R 2
(-1200 3600);
FORCEPROP 3 LASTPIN (-1150 3600) SIG_NAME M_G_CPU1_SA_DQ<22>
J 0
(-1140 3610);
DISPLAY 0.659574 (-1140 3610);
PAINT MONO (-1140 3610);
DISPLAY INVISIBLE (-1140 3610);
FORCEPROP 1 LASTPIN (-1150 3600) BN 22
J 2
(-1138 3608);
DISPLAY 0.680851 (-1138 3608);
PAINT GREEN (-1138 3608);
FORCEPROP 2 LAST CDS_LIB standard
J 0
(-1200 3600);
DISPLAY INVISIBLE (-1200 3600);
FORCEPROP 1 LAST BODY_TYPE PLUMBING
J 2
(-1200 3650);
DISPLAY 0.872340 (-1200 3650);
PAINT GREEN (-1200 3650);
DISPLAY INVISIBLE (-1200 3650);
FORCEPROP 1 LAST HDL_TAP TRUE
J 2
(-1525 3475);
DISPLAY 0.872340 (-1525 3475);
DISPLAY INVISIBLE (-1525 3475);
FORCEPROP 1 LAST PATH I81
J 2
(-1198 3600);
DISPLAY 0.872340 (-1198 3600);
PAINT GREEN (-1198 3600);
DISPLAY INVISIBLE (-1198 3600);
FORCEADD TAP..1
R 2
(-1200 3650);
FORCEPROP 3 LASTPIN (-1150 3650) SIG_NAME M_G_CPU1_SA_DQ<23>
J 0
(-1140 3660);
DISPLAY 0.659574 (-1140 3660);
PAINT MONO (-1140 3660);
DISPLAY INVISIBLE (-1140 3660);
FORCEPROP 1 LASTPIN (-1150 3650) BN 23
J 2
(-1138 3658);
DISPLAY 0.680851 (-1138 3658);
PAINT GREEN (-1138 3658);
FORCEPROP 2 LAST CDS_LIB standard
J 0
(-1200 3650);
DISPLAY INVISIBLE (-1200 3650);
FORCEPROP 1 LAST BODY_TYPE PLUMBING
J 2
(-1200 3700);
DISPLAY 0.872340 (-1200 3700);
PAINT GREEN (-1200 3700);
DISPLAY INVISIBLE (-1200 3700);
FORCEPROP 1 LAST HDL_TAP TRUE
J 2
(-1525 3525);
DISPLAY 0.872340 (-1525 3525);
DISPLAY INVISIBLE (-1525 3525);
FORCEPROP 1 LAST PATH I82
J 2
(-1198 3650);
DISPLAY 0.872340 (-1198 3650);
PAINT GREEN (-1198 3650);
DISPLAY INVISIBLE (-1198 3650);
FORCEADD TAP..1
R 2
(-1200 3700);
FORCEPROP 3 LASTPIN (-1150 3700) SIG_NAME M_G_CPU1_SA_DQ<24>
J 0
(-1140 3710);
DISPLAY 0.659574 (-1140 3710);
PAINT MONO (-1140 3710);
DISPLAY INVISIBLE (-1140 3710);
FORCEPROP 1 LASTPIN (-1150 3700) BN 24
J 2
(-1138 3708);
DISPLAY 0.680851 (-1138 3708);
PAINT GREEN (-1138 3708);
FORCEPROP 2 LAST CDS_LIB standard
J 0
(-1200 3700);
DISPLAY INVISIBLE (-1200 3700);
FORCEPROP 1 LAST BODY_TYPE PLUMBING
J 2
(-1200 3750);
DISPLAY 0.872340 (-1200 3750);
PAINT GREEN (-1200 3750);
DISPLAY INVISIBLE (-1200 3750);
FORCEPROP 1 LAST HDL_TAP TRUE
J 2
(-1525 3575);
DISPLAY 0.872340 (-1525 3575);
DISPLAY INVISIBLE (-1525 3575);
FORCEPROP 1 LAST PATH I83
J 2
(-1198 3700);
DISPLAY 0.872340 (-1198 3700);
PAINT GREEN (-1198 3700);
DISPLAY INVISIBLE (-1198 3700);
FORCEADD TAP..1
R 2
(-1200 3750);
FORCEPROP 3 LASTPIN (-1150 3750) SIG_NAME M_G_CPU1_SA_DQ<25>
J 0
(-1140 3760);
DISPLAY 0.659574 (-1140 3760);
PAINT MONO (-1140 3760);
DISPLAY INVISIBLE (-1140 3760);
FORCEPROP 1 LASTPIN (-1150 3750) BN 25
J 2
(-1138 3758);
DISPLAY 0.680851 (-1138 3758);
PAINT GREEN (-1138 3758);
FORCEPROP 2 LAST CDS_LIB standard
J 0
(-1200 3750);
DISPLAY INVISIBLE (-1200 3750);
FORCEPROP 1 LAST BODY_TYPE PLUMBING
J 2
(-1200 3800);
DISPLAY 0.872340 (-1200 3800);
PAINT GREEN (-1200 3800);
DISPLAY INVISIBLE (-1200 3800);
FORCEPROP 1 LAST HDL_TAP TRUE
J 2
(-1525 3625);
DISPLAY 0.872340 (-1525 3625);
DISPLAY INVISIBLE (-1525 3625);
FORCEPROP 1 LAST PATH I84
J 2
(-1198 3750);
DISPLAY 0.872340 (-1198 3750);
PAINT GREEN (-1198 3750);
DISPLAY INVISIBLE (-1198 3750);
FORCEADD TAP..1
R 2
(-1200 3800);
FORCEPROP 3 LASTPIN (-1150 3800) SIG_NAME M_G_CPU1_SA_DQ<26>
J 0
(-1140 3810);
DISPLAY 0.659574 (-1140 3810);
PAINT MONO (-1140 3810);
DISPLAY INVISIBLE (-1140 3810);
FORCEPROP 1 LASTPIN (-1150 3800) BN 26
J 2
(-1138 3808);
DISPLAY 0.680851 (-1138 3808);
PAINT GREEN (-1138 3808);
FORCEPROP 2 LAST CDS_LIB standard
J 0
(-1200 3800);
DISPLAY INVISIBLE (-1200 3800);
FORCEPROP 1 LAST BODY_TYPE PLUMBING
J 2
(-1200 3850);
DISPLAY 0.872340 (-1200 3850);
PAINT GREEN (-1200 3850);
DISPLAY INVISIBLE (-1200 3850);
FORCEPROP 1 LAST HDL_TAP TRUE
J 2
(-1525 3675);
DISPLAY 0.872340 (-1525 3675);
DISPLAY INVISIBLE (-1525 3675);
FORCEPROP 1 LAST PATH I85
J 2
(-1198 3800);
DISPLAY 0.872340 (-1198 3800);
PAINT GREEN (-1198 3800);
DISPLAY INVISIBLE (-1198 3800);
FORCEADD TAP..1
R 2
(-1200 3900);
FORCEPROP 3 LASTPIN (-1150 3900) SIG_NAME M_G_CPU1_SA_DQ<28>
J 0
(-1140 3910);
DISPLAY 0.659574 (-1140 3910);
PAINT MONO (-1140 3910);
DISPLAY INVISIBLE (-1140 3910);
FORCEPROP 1 LASTPIN (-1150 3900) BN 28
J 2
(-1138 3908);
DISPLAY 0.680851 (-1138 3908);
PAINT GREEN (-1138 3908);
FORCEPROP 2 LAST CDS_LIB standard
J 0
(-1200 3900);
DISPLAY INVISIBLE (-1200 3900);
FORCEPROP 1 LAST BODY_TYPE PLUMBING
J 2
(-1200 3950);
DISPLAY 0.872340 (-1200 3950);
PAINT GREEN (-1200 3950);
DISPLAY INVISIBLE (-1200 3950);
FORCEPROP 1 LAST HDL_TAP TRUE
J 2
(-1525 3775);
DISPLAY 0.872340 (-1525 3775);
DISPLAY INVISIBLE (-1525 3775);
FORCEPROP 1 LAST PATH I86
J 2
(-1198 3900);
DISPLAY 0.872340 (-1198 3900);
PAINT GREEN (-1198 3900);
DISPLAY INVISIBLE (-1198 3900);
FORCEADD TAP..1
R 2
(-1200 3850);
FORCEPROP 3 LASTPIN (-1150 3850) SIG_NAME M_G_CPU1_SA_DQ<27>
J 0
(-1140 3860);
DISPLAY 0.659574 (-1140 3860);
PAINT MONO (-1140 3860);
DISPLAY INVISIBLE (-1140 3860);
FORCEPROP 1 LASTPIN (-1150 3850) BN 27
J 2
(-1138 3858);
DISPLAY 0.680851 (-1138 3858);
PAINT GREEN (-1138 3858);
FORCEPROP 2 LAST CDS_LIB standard
J 0
(-1200 3850);
DISPLAY INVISIBLE (-1200 3850);
FORCEPROP 1 LAST BODY_TYPE PLUMBING
J 2
(-1200 3900);
DISPLAY 0.872340 (-1200 3900);
PAINT GREEN (-1200 3900);
DISPLAY INVISIBLE (-1200 3900);
FORCEPROP 1 LAST HDL_TAP TRUE
J 2
(-1525 3725);
DISPLAY 0.872340 (-1525 3725);
DISPLAY INVISIBLE (-1525 3725);
FORCEPROP 1 LAST PATH I87
J 2
(-1198 3850);
DISPLAY 0.872340 (-1198 3850);
PAINT GREEN (-1198 3850);
DISPLAY INVISIBLE (-1198 3850);
FORCEADD TAP..1
R 2
(-1200 3950);
FORCEPROP 3 LASTPIN (-1150 3950) SIG_NAME M_G_CPU1_SA_DQ<29>
J 0
(-1140 3960);
DISPLAY 0.659574 (-1140 3960);
PAINT MONO (-1140 3960);
DISPLAY INVISIBLE (-1140 3960);
FORCEPROP 1 LASTPIN (-1150 3950) BN 29
J 2
(-1138 3958);
DISPLAY 0.680851 (-1138 3958);
PAINT GREEN (-1138 3958);
FORCEPROP 2 LAST CDS_LIB standard
J 0
(-1200 3950);
DISPLAY INVISIBLE (-1200 3950);
FORCEPROP 1 LAST BODY_TYPE PLUMBING
J 2
(-1200 4000);
DISPLAY 0.872340 (-1200 4000);
PAINT GREEN (-1200 4000);
DISPLAY INVISIBLE (-1200 4000);
FORCEPROP 1 LAST HDL_TAP TRUE
J 2
(-1525 3825);
DISPLAY 0.872340 (-1525 3825);
DISPLAY INVISIBLE (-1525 3825);
FORCEPROP 1 LAST PATH I88
J 2
(-1198 3950);
DISPLAY 0.872340 (-1198 3950);
PAINT GREEN (-1198 3950);
DISPLAY INVISIBLE (-1198 3950);
FORCEADD TAP..1
R 2
(-1200 4000);
FORCEPROP 3 LASTPIN (-1150 4000) SIG_NAME M_G_CPU1_SA_DQ<30>
J 0
(-1140 4010);
DISPLAY 0.659574 (-1140 4010);
PAINT MONO (-1140 4010);
DISPLAY INVISIBLE (-1140 4010);
FORCEPROP 1 LASTPIN (-1150 4000) BN 30
J 2
(-1138 4008);
DISPLAY 0.680851 (-1138 4008);
PAINT GREEN (-1138 4008);
FORCEPROP 2 LAST CDS_LIB standard
J 0
(-1200 4000);
DISPLAY INVISIBLE (-1200 4000);
FORCEPROP 1 LAST BODY_TYPE PLUMBING
J 2
(-1200 4050);
DISPLAY 0.872340 (-1200 4050);
PAINT GREEN (-1200 4050);
DISPLAY INVISIBLE (-1200 4050);
FORCEPROP 1 LAST HDL_TAP TRUE
J 2
(-1525 3875);
DISPLAY 0.872340 (-1525 3875);
DISPLAY INVISIBLE (-1525 3875);
FORCEPROP 1 LAST PATH I89
J 2
(-1198 4000);
DISPLAY 0.872340 (-1198 4000);
PAINT GREEN (-1198 4000);
DISPLAY INVISIBLE (-1198 4000);
FORCEADD TAP..1
R 2
(-1200 100);
FORCEPROP 3 LASTPIN (-1150 100) SIG_NAME M_G_CPU1_SB_CB<0>
J 0
(-1140 110);
DISPLAY 0.659574 (-1140 110);
PAINT MONO (-1140 110);
DISPLAY INVISIBLE (-1140 110);
FORCEPROP 1 LASTPIN (-1150 100) BN 0
J 2
(-1138 108);
DISPLAY 0.680851 (-1138 108);
PAINT GREEN (-1138 108);
FORCEPROP 2 LAST CDS_LIB standard
J 0
(-1200 100);
DISPLAY INVISIBLE (-1200 100);
FORCEPROP 1 LAST BODY_TYPE PLUMBING
J 2
(-1200 150);
DISPLAY 0.872340 (-1200 150);
PAINT GREEN (-1200 150);
DISPLAY INVISIBLE (-1200 150);
FORCEPROP 1 LAST HDL_TAP TRUE
J 2
(-1525 -25);
DISPLAY 0.872340 (-1525 -25);
DISPLAY INVISIBLE (-1525 -25);
FORCEPROP 1 LAST PATH I9
J 2
(-1198 100);
DISPLAY 0.872340 (-1198 100);
PAINT GREEN (-1198 100);
DISPLAY INVISIBLE (-1198 100);
FORCEADD TAP..1
R 2
(-1200 4050);
FORCEPROP 3 LASTPIN (-1150 4050) SIG_NAME M_G_CPU1_SA_DQ<31>
J 0
(-1140 4060);
DISPLAY 0.659574 (-1140 4060);
PAINT MONO (-1140 4060);
DISPLAY INVISIBLE (-1140 4060);
FORCEPROP 1 LASTPIN (-1150 4050) BN 31
J 2
(-1138 4058);
DISPLAY 0.680851 (-1138 4058);
PAINT GREEN (-1138 4058);
FORCEPROP 2 LAST CDS_LIB standard
J 0
(-1200 4050);
DISPLAY INVISIBLE (-1200 4050);
FORCEPROP 1 LAST BODY_TYPE PLUMBING
J 2
(-1200 4100);
DISPLAY 0.872340 (-1200 4100);
PAINT GREEN (-1200 4100);
DISPLAY INVISIBLE (-1200 4100);
FORCEPROP 1 LAST HDL_TAP TRUE
J 2
(-1525 3925);
DISPLAY 0.872340 (-1525 3925);
DISPLAY INVISIBLE (-1525 3925);
FORCEPROP 1 LAST PATH I90
J 2
(-1198 4050);
DISPLAY 0.872340 (-1198 4050);
PAINT GREEN (-1198 4050);
DISPLAY INVISIBLE (-1198 4050);
FORCEADD OFFPAGE..4
(3325 -150);
FORCEPROP 2 LAST $XR1 111 
J 0
(3631 -150);
DISPLAY 0.638298 (3631 -150);
PAINT MONO (3631 -150);
FORCEPROP 2 LAST $XR0 110 
J 0
(3511 -150);
DISPLAY 0.638298 (3511 -150);
PAINT MONO (3511 -150);
FORCEPROP 2 LAST CDS_LIB standard
J 0
(3325 -150);
PAINT MONO (3325 -150);
DISPLAY INVISIBLE (3325 -150);
FORCEPROP 1 LAST OFFPAGE TRUE
J 0
(3650 -275);
DISPLAY 1.170213 (3650 -275);
PAINT GREEN (3650 -275);
DISPLAY INVISIBLE (3650 -275);
FORCEPROP 1 LAST COMMENT_BODY TRUE
J 0
(3300 -250);
DISPLAY 1.170213 (3300 -250);
PAINT GREEN (3300 -250);
DISPLAY INVISIBLE (3300 -250);
FORCEPROP 2 LAST PATH I91
J 0
(3500 -75);
DISPLAY 1.021277 (3500 -75);
DISPLAY INVISIBLE (3500 -75);
FORCEADD OFFPAGE..4
(3325 -50);
FORCEPROP 2 LAST $XR0 110 
J 0
(3511 -50);
DISPLAY 0.638298 (3511 -50);
PAINT MONO (3511 -50);
FORCEPROP 2 LAST CDS_LIB standard
J 0
(3325 -50);
PAINT MONO (3325 -50);
DISPLAY INVISIBLE (3325 -50);
FORCEPROP 1 LAST OFFPAGE TRUE
J 0
(3650 -175);
DISPLAY 1.170213 (3650 -175);
PAINT GREEN (3650 -175);
DISPLAY INVISIBLE (3650 -175);
FORCEPROP 1 LAST COMMENT_BODY TRUE
J 0
(3300 -150);
DISPLAY 1.170213 (3300 -150);
PAINT GREEN (3300 -150);
DISPLAY INVISIBLE (3300 -150);
FORCEPROP 2 LAST PATH I92
J 0
(3500 25);
DISPLAY 1.021277 (3500 25);
DISPLAY INVISIBLE (3500 25);
FORCEADD OFFPAGE..4
(3325 0);
FORCEPROP 2 LAST $XR0 111 
J 0
(3511 0);
DISPLAY 0.638298 (3511 0);
PAINT MONO (3511 0);
FORCEPROP 2 LAST CDS_LIB standard
J 0
(3325 0);
PAINT MONO (3325 0);
DISPLAY INVISIBLE (3325 0);
FORCEPROP 1 LAST OFFPAGE TRUE
J 0
(3650 -125);
DISPLAY 1.170213 (3650 -125);
PAINT GREEN (3650 -125);
DISPLAY INVISIBLE (3650 -125);
FORCEPROP 1 LAST COMMENT_BODY TRUE
J 0
(3300 -100);
DISPLAY 1.170213 (3300 -100);
PAINT GREEN (3300 -100);
DISPLAY INVISIBLE (3300 -100);
FORCEPROP 2 LAST PATH I93
J 0
(3500 75);
DISPLAY 1.021277 (3500 75);
DISPLAY INVISIBLE (3500 75);
FORCEADD TAP..1
(2225 450);
FORCEPROP 3 LASTPIN (2175 450) SIG_NAME M_G_CPU1_SB_CS_N<3>
J 0
(2185 460);
DISPLAY 0.659574 (2185 460);
PAINT MONO (2185 460);
DISPLAY INVISIBLE (2185 460);
FORCEPROP 1 LASTPIN (2175 450) BN 3
J 0
(2163 458);
DISPLAY 0.680851 (2163 458);
PAINT GREEN (2163 458);
FORCEPROP 2 LAST CDS_LIB standard
J 0
(2225 450);
DISPLAY INVISIBLE (2225 450);
FORCEPROP 1 LAST BODY_TYPE PLUMBING
J 0
(2225 500);
DISPLAY 0.872340 (2225 500);
PAINT GREEN (2225 500);
DISPLAY INVISIBLE (2225 500);
FORCEPROP 1 LAST HDL_TAP TRUE
J 0
(2550 325);
DISPLAY 0.872340 (2550 325);
DISPLAY INVISIBLE (2550 325);
FORCEPROP 1 LAST PATH I94
J 0
(2223 450);
DISPLAY 0.872340 (2223 450);
PAINT GREEN (2223 450);
DISPLAY INVISIBLE (2223 450);
FORCEADD TAP..1
(2225 350);
FORCEPROP 3 LASTPIN (2175 350) SIG_NAME M_G_CPU1_SB_CS_N<1>
J 0
(2185 360);
DISPLAY 0.659574 (2185 360);
PAINT MONO (2185 360);
DISPLAY INVISIBLE (2185 360);
FORCEPROP 1 LASTPIN (2175 350) BN 1
J 0
(2163 358);
DISPLAY 0.680851 (2163 358);
PAINT GREEN (2163 358);
FORCEPROP 2 LAST CDS_LIB standard
J 0
(2225 350);
DISPLAY INVISIBLE (2225 350);
FORCEPROP 1 LAST BODY_TYPE PLUMBING
J 0
(2225 400);
DISPLAY 0.872340 (2225 400);
PAINT GREEN (2225 400);
DISPLAY INVISIBLE (2225 400);
FORCEPROP 1 LAST HDL_TAP TRUE
J 0
(2550 225);
DISPLAY 0.872340 (2550 225);
DISPLAY INVISIBLE (2550 225);
FORCEPROP 1 LAST PATH I95
J 0
(2223 350);
DISPLAY 0.872340 (2223 350);
PAINT GREEN (2223 350);
DISPLAY INVISIBLE (2223 350);
FORCEADD TAP..1
(2225 300);
FORCEPROP 3 LASTPIN (2175 300) SIG_NAME M_G_CPU1_SB_CS_N<0>
J 0
(2185 310);
DISPLAY 0.659574 (2185 310);
PAINT MONO (2185 310);
DISPLAY INVISIBLE (2185 310);
FORCEPROP 1 LASTPIN (2175 300) BN 0
J 0
(2163 308);
DISPLAY 0.680851 (2163 308);
PAINT GREEN (2163 308);
FORCEPROP 2 LAST CDS_LIB standard
J 0
(2225 300);
DISPLAY INVISIBLE (2225 300);
FORCEPROP 1 LAST BODY_TYPE PLUMBING
J 0
(2225 350);
DISPLAY 0.872340 (2225 350);
PAINT GREEN (2225 350);
DISPLAY INVISIBLE (2225 350);
FORCEPROP 1 LAST HDL_TAP TRUE
J 0
(2550 175);
DISPLAY 0.872340 (2550 175);
DISPLAY INVISIBLE (2550 175);
FORCEPROP 1 LAST PATH I96
J 0
(2223 300);
DISPLAY 0.872340 (2223 300);
PAINT GREEN (2223 300);
DISPLAY INVISIBLE (2223 300);
FORCEADD TAP..1
(2225 400);
FORCEPROP 3 LASTPIN (2175 400) SIG_NAME M_G_CPU1_SB_CS_N<2>
J 0
(2185 410);
DISPLAY 0.659574 (2185 410);
PAINT MONO (2185 410);
DISPLAY INVISIBLE (2185 410);
FORCEPROP 1 LASTPIN (2175 400) BN 2
J 0
(2163 408);
DISPLAY 0.680851 (2163 408);
PAINT GREEN (2163 408);
FORCEPROP 2 LAST CDS_LIB standard
J 0
(2225 400);
DISPLAY INVISIBLE (2225 400);
FORCEPROP 1 LAST BODY_TYPE PLUMBING
J 0
(2225 450);
DISPLAY 0.872340 (2225 450);
PAINT GREEN (2225 450);
DISPLAY INVISIBLE (2225 450);
FORCEPROP 1 LAST HDL_TAP TRUE
J 0
(2550 275);
DISPLAY 0.872340 (2550 275);
DISPLAY INVISIBLE (2550 275);
FORCEPROP 1 LAST PATH I97
J 0
(2223 400);
DISPLAY 0.872340 (2223 400);
PAINT GREEN (2223 400);
DISPLAY INVISIBLE (2223 400);
FORCEADD TAP..1
(2225 700);
FORCEPROP 3 LASTPIN (2175 700) SIG_NAME M_G_CPU1_SA_CS_N<2>
J 0
(2185 710);
DISPLAY 0.659574 (2185 710);
PAINT MONO (2185 710);
DISPLAY INVISIBLE (2185 710);
FORCEPROP 1 LASTPIN (2175 700) BN 2
J 0
(2163 708);
DISPLAY 0.680851 (2163 708);
PAINT GREEN (2163 708);
FORCEPROP 2 LAST CDS_LIB standard
J 0
(2225 700);
DISPLAY INVISIBLE (2225 700);
FORCEPROP 1 LAST BODY_TYPE PLUMBING
J 0
(2225 750);
DISPLAY 0.872340 (2225 750);
PAINT GREEN (2225 750);
DISPLAY INVISIBLE (2225 750);
FORCEPROP 1 LAST HDL_TAP TRUE
J 0
(2550 575);
DISPLAY 0.872340 (2550 575);
DISPLAY INVISIBLE (2550 575);
FORCEPROP 1 LAST PATH I98
J 0
(2223 700);
DISPLAY 0.872340 (2223 700);
PAINT GREEN (2223 700);
DISPLAY INVISIBLE (2223 700);
FORCEADD TAP..1
(2225 600);
FORCEPROP 3 LASTPIN (2175 600) SIG_NAME M_G_CPU1_SA_CS_N<0>
J 0
(2185 610);
DISPLAY 0.659574 (2185 610);
PAINT MONO (2185 610);
DISPLAY INVISIBLE (2185 610);
FORCEPROP 1 LASTPIN (2175 600) BN 0
J 0
(2163 608);
DISPLAY 0.680851 (2163 608);
PAINT GREEN (2163 608);
FORCEPROP 2 LAST CDS_LIB standard
J 0
(2225 600);
DISPLAY INVISIBLE (2225 600);
FORCEPROP 1 LAST BODY_TYPE PLUMBING
J 0
(2225 650);
DISPLAY 0.872340 (2225 650);
PAINT GREEN (2225 650);
DISPLAY INVISIBLE (2225 650);
FORCEPROP 1 LAST HDL_TAP TRUE
J 0
(2550 475);
DISPLAY 0.872340 (2550 475);
DISPLAY INVISIBLE (2550 475);
FORCEPROP 1 LAST PATH I99
J 0
(2223 600);
DISPLAY 0.872340 (2223 600);
PAINT GREEN (2223 600);
DISPLAY INVISIBLE (2223 600);
FORCEADD QUANTA_TITLE_BLOCK_C..1
(5150 -1450);
FORCEPROP 0 LAST CDS_CON_LAST_MODIFIED Fri Aug 25 14:00:39 2023
J 0
(3265 -1435);
PAINT MONO (3265 -1435);
DISPLAY INVISIBLE (3265 -1435);
FORCEPROP 1 LAST CUSTOM_TXT_CDS <CON_LAST_MODIFIED>
J 0
(3265 -1435);
DISPLAY 0.978723 (3265 -1435);
FORCEPROP 2 LAST CUSTOM_TXT_CDS <XR_PAGE_TITLE>
J 0
(-2740 3800);
DISPLAY 0.638298 (-2740 3800);
PAINT PINK (-2740 3800);
DISPLAY INVISIBLE (-2740 3800);
FORCEPROP 2 LAST CUSTOM_TXT_CDS <Q_NUMBER>
J 0
(3747 -1347);
DISPLAY 1.212766 (3747 -1347);
FORCEPROP 1 LAST CUSTOM_TXT_CDS <NAME_2>
J 0
(1975 -1400);
FORCEPROP 1 LAST CUSTOM_TXT_CDS <NAME_1>
J 0
(1975 -1275);
FORCEPROP 1 LAST CUSTOM_TXT_CDS <Q_PROJ>
J 0
(2768 -1348);
DISPLAY 1.212766 (2768 -1348);
FORCEPROP 1 LAST CUSTOM_TXT_CDS <Q_REV>
J 0
(4966 -1347);
DISPLAY 1.212766 (4966 -1347);
FORCEPROP 1 LAST CUSTOM_TXT_CDS <CON_PAGE_NUM> OF <CON_TOTAL_PAGES>
J 0
(4704 -1432);
DISPLAY 0.978723 (4704 -1432);
FORCEPROP 1 LAST Q_TITLE SPR CPU1 - DDR CH G (14 OF 30)
J 0
(-4216 -1424);
DISPLAY 1.957447 (-4216 -1424);
PAINT GREEN (-4216 -1424);
FORCEPROP 1 LAST Q_DEPT 
J 1
(1387 -1401);
DISPLAY 1.957447 (1387 -1401);
PAINT GREEN (1387 -1401);
FORCEPROP 1 LAST COMMENT_BODY TRUE
J 0
(5162 -1463);
DISPLAY 0.978723 (5162 -1463);
PAINT GREEN (5162 -1463);
DISPLAY INVISIBLE (5162 -1463);
FORCEPROP 2 LAST CDS_XR_PAGE_TITLE CR-57 : @S9S_MB_2U_LIB.S9S_MB_2U(SCH_1):PAGE57
J 0
(-2740 3800);
DISPLAY 0.638298 (-2740 3800);
PAINT PINK (-2740 3800);
DISPLAY INVISIBLE (-2740 3800);
FORCEPROP 2 LAST PAGE_BORDER TRUE
J 0
(-2740 3800);
DISPLAY 0.638298 (-2740 3800);
PAINT PINK (-2740 3800);
DISPLAY INVISIBLE (-2740 3800);
FORCEPROP 1 LAST CDS_LMAN_SYM_OUTLINE -9475,6775,100,-125
J 0
(5150 -1450);
DISPLAY 0.468085 (5150 -1450);
PAINT GREEN (5150 -1450);
DISPLAY INVISIBLE (5150 -1450);
FORCEPROP 2 LAST CDS_LIB pure_quanta
J 0
(5150 -1450);
PAINT MONO (5150 -1450);
DISPLAY INVISIBLE (5150 -1450);
WIRE 17 -1 (2275 1775)(3275 1775);
FORCEPROP 2 LAST SIG_NAME M_G_CPU1_SA_CA<6:0>
J 0
(2415 1785);
DISPLAY 0.680851 (2415 1785);
PAINT WHITE (2415 1785);
WIRE 17 -1 (2275 1725)(2275 1775);
WIRE 17 -1 (2275 1675)(2275 1725);
WIRE 17 -1 (2275 1625)(2275 1675);
WIRE 17 -1 (2275 1575)(2275 1625);
WIRE 17 -1 (2275 1525)(2275 1575);
WIRE 17 -1 (2275 1475)(2275 1525);
WIRE 17 -1 (2275 775)(3275 775);
FORCEPROP 2 LAST SIG_NAME M_G_CPU1_SA_CS_N<3:0>
J 0
(2415 785);
DISPLAY 0.680851 (2415 785);
PAINT WHITE (2415 785);
WIRE 17 -1 (2275 725)(2275 775);
WIRE 17 -1 (2275 675)(2275 725);
WIRE 17 -1 (2275 625)(2275 675);
WIRE 17 -1 (2275 3525)(3275 3525);
FORCEPROP 2 LAST SIG_NAME M_G_CPU1_SA_DQS_DN<9:0>
J 0
(2415 3535);
DISPLAY 0.680851 (2415 3535);
PAINT WHITE (2415 3535);
WIRE 17 -1 (2275 3475)(2275 3525);
WIRE 17 -1 (2275 3425)(2275 3475);
WIRE 17 -1 (2275 3375)(2275 3425);
WIRE 17 -1 (2275 3325)(2275 3375);
WIRE 17 -1 (2275 3275)(2275 3325);
WIRE 17 -1 (2275 3225)(2275 3275);
WIRE 17 -1 (2275 3175)(2275 3225);
WIRE 17 -1 (2275 3125)(2275 3175);
WIRE 17 -1 (2275 3075)(2275 3125);
WIRE 17 -1 (2275 4075)(3275 4075);
FORCEPROP 2 LAST SIG_NAME M_G_CPU1_SA_DQS_DP<9:0>
J 0
(2415 4085);
DISPLAY 0.680851 (2415 4085);
PAINT WHITE (2415 4085);
WIRE 17 -1 (2275 4025)(2275 4075);
WIRE 17 -1 (2275 3975)(2275 4025);
WIRE 17 -1 (2275 3925)(2275 3975);
WIRE 17 -1 (2275 3875)(2275 3925);
WIRE 17 -1 (2275 3825)(2275 3875);
WIRE 17 -1 (2275 3775)(2275 3825);
WIRE 17 -1 (2275 3725)(2275 3775);
WIRE 17 -1 (2275 3675)(2275 3725);
WIRE 17 -1 (2275 3625)(2275 3675);
WIRE 17 -1 (2275 1275)(3275 1275);
FORCEPROP 2 LAST SIG_NAME M_G_CPU1_SB_CA<6:0>
J 0
(2415 1285);
DISPLAY 0.680851 (2415 1285);
PAINT WHITE (2415 1285);
WIRE 17 -1 (2275 1225)(2275 1275);
WIRE 17 -1 (2275 1175)(2275 1225);
WIRE 17 -1 (2275 1125)(2275 1175);
WIRE 17 -1 (2275 1075)(2275 1125);
WIRE 17 -1 (2275 1025)(2275 1075);
WIRE 17 -1 (2275 975)(2275 1025);
WIRE 17 -1 (2275 475)(3275 475);
FORCEPROP 2 LAST SIG_NAME M_G_CPU1_SB_CS_N<3:0>
J 0
(2415 485);
DISPLAY 0.680851 (2415 485);
PAINT WHITE (2415 485);
WIRE 17 -1 (2275 425)(2275 475);
WIRE 17 -1 (2275 375)(2275 425);
WIRE 17 -1 (2275 325)(2275 375);
WIRE 17 -1 (2275 2375)(3275 2375);
FORCEPROP 2 LAST SIG_NAME M_G_CPU1_SB_DQS_DN<9:0>
J 0
(2415 2385);
DISPLAY 0.680851 (2415 2385);
PAINT WHITE (2415 2385);
WIRE 17 -1 (2275 2325)(2275 2375);
WIRE 17 -1 (2275 2275)(2275 2325);
WIRE 17 -1 (2275 2225)(2275 2275);
WIRE 17 -1 (2275 2175)(2275 2225);
WIRE 17 -1 (2275 2125)(2275 2175);
WIRE 17 -1 (2275 2075)(2275 2125);
WIRE 17 -1 (2275 2025)(2275 2075);
WIRE 17 -1 (2275 1975)(2275 2025);
WIRE 17 -1 (2275 1925)(2275 1975);
WIRE 17 -1 (2275 2925)(3275 2925);
FORCEPROP 2 LAST SIG_NAME M_G_CPU1_SB_DQS_DP<9:0>
J 0
(2415 2935);
DISPLAY 0.680851 (2415 2935);
PAINT WHITE (2415 2935);
WIRE 17 -1 (2275 2875)(2275 2925);
WIRE 17 -1 (2275 2825)(2275 2875);
WIRE 17 -1 (2275 2775)(2275 2825);
WIRE 17 -1 (2275 2725)(2275 2775);
WIRE 17 -1 (2275 2675)(2275 2725);
WIRE 17 -1 (2275 2625)(2275 2675);
WIRE 17 -1 (2275 2575)(2275 2625);
WIRE 17 -1 (2275 2525)(2275 2575);
WIRE 17 -1 (2275 2475)(2275 2525);
WIRE 17 -1 (-1250 125)(-1250 175);
WIRE 17 -1 (-1250 175)(-1250 225);
WIRE 17 -1 (-1250 225)(-1250 275);
WIRE 17 -1 (-1250 275)(-1250 325);
WIRE 17 -1 (-1250 325)(-1250 375);
WIRE 17 -1 (-1250 375)(-1250 425);
WIRE 17 -1 (-1250 425)(-1250 475);
WIRE 17 -1 (-2175 475)(-1250 475);
FORCEPROP 2 LAST SIG_NAME M_G_CPU1_SB_CB<7:0>
J 0
(-2035 485);
DISPLAY 0.680851 (-2035 485);
PAINT WHITE (-2035 485);
WIRE 17 -1 (-1250 525)(-1250 575);
WIRE 17 -1 (-1250 575)(-1250 625);
WIRE 17 -1 (-1250 625)(-1250 675);
WIRE 17 -1 (-1250 675)(-1250 725);
WIRE 17 -1 (-1250 725)(-1250 775);
WIRE 17 -1 (-1250 775)(-1250 825);
WIRE 17 -1 (-1250 825)(-1250 875);
WIRE 17 -1 (-1250 875)(-1250 925);
WIRE 17 -1 (-1250 925)(-1250 975);
WIRE 17 -1 (-1250 975)(-1250 1025);
WIRE 17 -1 (-1250 1025)(-1250 1075);
WIRE 17 -1 (-1250 1075)(-1250 1125);
WIRE 17 -1 (-1250 1125)(-1250 1175);
WIRE 17 -1 (-1250 1175)(-1250 1225);
WIRE 17 -1 (-1250 1225)(-1250 1275);
WIRE 17 -1 (-1250 1275)(-1250 1325);
WIRE 17 -1 (-1250 1325)(-1250 1375);
WIRE 17 -1 (-1250 1375)(-1250 1425);
WIRE 17 -1 (-1250 1425)(-1250 1475);
WIRE 17 -1 (-1250 1475)(-1250 1525);
WIRE 17 -1 (-1250 1525)(-1250 1575);
WIRE 17 -1 (-1250 1575)(-1250 1625);
WIRE 17 -1 (-1250 1625)(-1250 1675);
WIRE 17 -1 (-1250 1675)(-1250 1725);
WIRE 17 -1 (-1250 1725)(-1250 1775);
WIRE 17 -1 (-1250 1775)(-1250 1825);
WIRE 17 -1 (-1250 1825)(-1250 1875);
WIRE 17 -1 (-1250 1875)(-1250 1925);
WIRE 17 -1 (-1250 1925)(-1250 1975);
WIRE 17 -1 (-1250 1975)(-1250 2025);
WIRE 17 -1 (-1250 2025)(-1250 2075);
WIRE 17 -1 (-2175 2075)(-1250 2075);
FORCEPROP 2 LAST SIG_NAME M_G_CPU1_SB_DQ<31:0>
J 0
(-2035 2085);
DISPLAY 0.680851 (-2035 2085);
PAINT WHITE (-2035 2085);
WIRE 17 -1 (-1250 2125)(-1250 2175);
WIRE 17 -1 (-1250 2175)(-1250 2225);
WIRE 17 -1 (-1250 2225)(-1250 2275);
WIRE 17 -1 (-1250 2275)(-1250 2325);
WIRE 17 -1 (-1250 2325)(-1250 2375);
WIRE 17 -1 (-1250 2375)(-1250 2425);
WIRE 17 -1 (-1250 2425)(-1250 2475);
WIRE 17 -1 (-2175 2475)(-1250 2475);
FORCEPROP 2 LAST SIG_NAME M_G_CPU1_SA_CB<7:0>
J 0
(-2035 2485);
DISPLAY 0.680851 (-2035 2485);
PAINT WHITE (-2035 2485);
WIRE 17 -1 (-1250 2525)(-1250 2575);
WIRE 17 -1 (-1250 2575)(-1250 2625);
WIRE 17 -1 (-1250 2625)(-1250 2675);
WIRE 17 -1 (-1250 2675)(-1250 2725);
WIRE 17 -1 (-1250 2725)(-1250 2775);
WIRE 17 -1 (-1250 2775)(-1250 2825);
WIRE 17 -1 (-1250 2825)(-1250 2875);
WIRE 17 -1 (-1250 2875)(-1250 2925);
WIRE 17 -1 (-1250 2925)(-1250 2975);
WIRE 17 -1 (-1250 2975)(-1250 3025);
WIRE 17 -1 (-1250 3025)(-1250 3075);
WIRE 17 -1 (-1250 3075)(-1250 3125);
WIRE 17 -1 (-1250 3125)(-1250 3175);
WIRE 17 -1 (-1250 3175)(-1250 3225);
WIRE 17 -1 (-1250 3225)(-1250 3275);
WIRE 17 -1 (-1250 3275)(-1250 3325);
WIRE 17 -1 (-1250 3325)(-1250 3375);
WIRE 17 -1 (-1250 3375)(-1250 3425);
WIRE 17 -1 (-1250 3425)(-1250 3475);
WIRE 17 -1 (-1250 3475)(-1250 3525);
WIRE 17 -1 (-1250 3525)(-1250 3575);
WIRE 17 -1 (-1250 3575)(-1250 3625);
WIRE 17 -1 (-1250 3625)(-1250 3675);
WIRE 17 -1 (-1250 3675)(-1250 3725);
WIRE 17 -1 (-1250 3725)(-1250 3775);
WIRE 17 -1 (-1250 3775)(-1250 3825);
WIRE 17 -1 (-1250 3825)(-1250 3875);
WIRE 17 -1 (-1250 3875)(-1250 3925);
WIRE 17 -1 (-1250 3925)(-1250 3975);
WIRE 17 -1 (-1250 3975)(-1250 4025);
WIRE 17 -1 (-1250 4025)(-1250 4075);
WIRE 17 -1 (-2175 4075)(-1250 4075);
FORCEPROP 2 LAST SIG_NAME M_G_CPU1_SA_DQ<31:0>
J 0
(-2035 4085);
DISPLAY 0.680851 (-2035 4085);
PAINT WHITE (-2035 4085);
WIRE 17 -1 (-1250 -25)(-1250 25);
WIRE 17 -1 (-2175 25)(-1250 25);
FORCEPROP 2 LAST SIG_NAME M_G_CPU1_CLK_DP<1:0>
J 0
(-2035 35);
DISPLAY 0.680851 (-2035 35);
PAINT WHITE (-2035 35);
WIRE 17 -1 (-1250 -125)(-1250 -75);
WIRE 17 -1 (-2175 -75)(-1250 -75);
FORCEPROP 2 LAST SIG_NAME M_G_CPU1_CLK_DN<1:0>
J 0
(-2035 -65);
DISPLAY 0.680851 (-2035 -65);
PAINT WHITE (-2035 -65);
WIRE 16 -1 (-1150 -150)(-700 -150);
WIRE 16 -1 (-1150 -100)(-700 -100);
WIRE 16 -1 (-1150 0)(-700 0);
WIRE 16 -1 (-1150 -50)(-700 -50);
WIRE 16 -1 (-1150 4050)(-700 4050);
WIRE 16 -1 (-1150 4000)(-700 4000);
WIRE 16 -1 (-1150 3950)(-700 3950);
WIRE 16 -1 (-1150 3900)(-700 3900);
WIRE 16 -1 (-1150 3850)(-700 3850);
WIRE 16 -1 (-1150 3800)(-700 3800);
WIRE 16 -1 (-1150 3750)(-700 3750);
WIRE 16 -1 (-1150 3700)(-700 3700);
WIRE 16 -1 (-1150 3650)(-700 3650);
WIRE 16 -1 (-1150 3600)(-700 3600);
WIRE 16 -1 (-1150 3550)(-700 3550);
WIRE 16 -1 (-1150 3500)(-700 3500);
WIRE 16 -1 (-1150 3450)(-700 3450);
WIRE 16 -1 (-1150 3400)(-700 3400);
WIRE 16 -1 (-1150 3350)(-700 3350);
WIRE 16 -1 (-1150 3300)(-700 3300);
WIRE 16 -1 (-1150 3250)(-700 3250);
WIRE 16 -1 (-1150 3200)(-700 3200);
WIRE 16 -1 (-1150 3150)(-700 3150);
WIRE 16 -1 (-1150 3100)(-700 3100);
WIRE 16 -1 (-1150 3050)(-700 3050);
WIRE 16 -1 (-1150 3000)(-700 3000);
WIRE 16 -1 (-1150 2950)(-700 2950);
WIRE 16 -1 (-1150 2900)(-700 2900);
WIRE 16 -1 (-1150 2850)(-700 2850);
WIRE 16 -1 (-1150 2800)(-700 2800);
WIRE 16 -1 (-1150 2750)(-700 2750);
WIRE 16 -1 (-1150 2700)(-700 2700);
WIRE 16 -1 (-1150 2650)(-700 2650);
WIRE 16 -1 (-1150 2600)(-700 2600);
WIRE 16 -1 (-1150 2550)(-700 2550);
WIRE 16 -1 (-1150 2500)(-700 2500);
WIRE 16 -1 (-1150 2450)(-700 2450);
WIRE 16 -1 (-1150 2400)(-700 2400);
WIRE 16 -1 (-1150 2350)(-700 2350);
WIRE 16 -1 (-1150 2300)(-700 2300);
WIRE 16 -1 (-1150 2250)(-700 2250);
WIRE 16 -1 (-1150 2200)(-700 2200);
WIRE 16 -1 (-1150 2150)(-700 2150);
WIRE 16 -1 (-1150 2100)(-700 2100);
WIRE 16 -1 (-1150 2050)(-700 2050);
WIRE 16 -1 (-1150 2000)(-700 2000);
WIRE 16 -1 (-1150 1950)(-700 1950);
WIRE 16 -1 (-1150 1900)(-700 1900);
WIRE 16 -1 (-1150 1850)(-700 1850);
WIRE 16 -1 (-1150 1800)(-700 1800);
WIRE 16 -1 (-1150 1750)(-700 1750);
WIRE 16 -1 (-1150 1700)(-700 1700);
WIRE 16 -1 (-1150 1650)(-700 1650);
WIRE 16 -1 (-1150 1600)(-700 1600);
WIRE 16 -1 (-1150 1550)(-700 1550);
WIRE 16 -1 (-1150 1500)(-700 1500);
WIRE 16 -1 (-1150 1450)(-700 1450);
WIRE 16 -1 (-1150 1400)(-700 1400);
WIRE 16 -1 (-1150 1350)(-700 1350);
WIRE 16 -1 (-1150 1300)(-700 1300);
WIRE 16 -1 (-1150 1250)(-700 1250);
WIRE 16 -1 (-1150 1200)(-700 1200);
WIRE 16 -1 (-1150 1150)(-700 1150);
WIRE 16 -1 (-1150 1100)(-700 1100);
WIRE 16 -1 (-1150 1050)(-700 1050);
WIRE 16 -1 (-1150 1000)(-700 1000);
WIRE 16 -1 (-1150 950)(-700 950);
WIRE 16 -1 (-1150 900)(-700 900);
WIRE 16 -1 (-1150 850)(-700 850);
WIRE 16 -1 (-1150 800)(-700 800);
WIRE 16 -1 (-1150 750)(-700 750);
WIRE 16 -1 (-1150 700)(-700 700);
WIRE 16 -1 (-1150 650)(-700 650);
WIRE 16 -1 (-1150 600)(-700 600);
WIRE 16 -1 (-1150 550)(-700 550);
WIRE 16 -1 (-1150 500)(-700 500);
WIRE 16 -1 (-1150 450)(-700 450);
WIRE 16 -1 (-1150 400)(-700 400);
WIRE 16 -1 (-1150 350)(-700 350);
WIRE 16 -1 (-1150 300)(-700 300);
WIRE 16 -1 (-1150 250)(-700 250);
WIRE 16 -1 (-1150 200)(-700 200);
WIRE 16 -1 (-1150 150)(-700 150);
WIRE 16 -1 (-1150 100)(-700 100);
WIRE 16 -1 (3275 900)(1750 900);
FORCEPROP 2 LAST SIG_NAME M_G_CPU1_SB_PAR
J 0
(2384 909);
DISPLAY 0.680851 (2384 909);
PAINT WHITE (2384 909);
WIRE 16 -1 (1750 2450)(2175 2450);
WIRE 16 -1 (1750 2500)(2175 2500);
WIRE 16 -1 (1750 2550)(2175 2550);
WIRE 16 -1 (1750 2600)(2175 2600);
WIRE 16 -1 (1750 2650)(2175 2650);
WIRE 16 -1 (1750 2700)(2175 2700);
WIRE 16 -1 (1750 2750)(2175 2750);
WIRE 16 -1 (1750 2800)(2175 2800);
WIRE 16 -1 (1750 2850)(2175 2850);
WIRE 16 -1 (1750 2900)(2175 2900);
WIRE 16 -1 (1750 1900)(2175 1900);
WIRE 16 -1 (1750 1950)(2175 1950);
WIRE 16 -1 (1750 2000)(2175 2000);
WIRE 16 -1 (1750 2050)(2175 2050);
WIRE 16 -1 (1750 2100)(2175 2100);
WIRE 16 -1 (1750 2150)(2175 2150);
WIRE 16 -1 (1750 2200)(2175 2200);
WIRE 16 -1 (1750 2250)(2175 2250);
WIRE 16 -1 (1750 2300)(2175 2300);
WIRE 16 -1 (1750 2350)(2175 2350);
WIRE 16 -1 (1750 300)(2175 300);
WIRE 16 -1 (1750 350)(2175 350);
WIRE 16 -1 (1750 400)(2175 400);
WIRE 16 -1 (1750 450)(2175 450);
WIRE 16 -1 (1750 950)(2175 950);
WIRE 16 -1 (1750 1000)(2175 1000);
WIRE 16 -1 (1750 1050)(2175 1050);
WIRE 16 -1 (1750 1100)(2175 1100);
WIRE 16 -1 (1750 1150)(2175 1150);
WIRE 16 -1 (1750 1200)(2175 1200);
WIRE 16 -1 (1750 1250)(2175 1250);
WIRE 16 -1 (3275 1400)(1750 1400);
FORCEPROP 2 LAST SIG_NAME M_G_CPU1_SA_PAR
J 0
(2384 1409);
DISPLAY 0.680851 (2384 1409);
PAINT WHITE (2384 1409);
WIRE 16 -1 (1750 3600)(2175 3600);
WIRE 16 -1 (1750 3650)(2175 3650);
WIRE 16 -1 (1750 3700)(2175 3700);
WIRE 16 -1 (1750 3750)(2175 3750);
WIRE 16 -1 (1750 3800)(2175 3800);
WIRE 16 -1 (1750 3850)(2175 3850);
WIRE 16 -1 (1750 3900)(2175 3900);
WIRE 16 -1 (1750 3950)(2175 3950);
WIRE 16 -1 (1750 4000)(2175 4000);
WIRE 16 -1 (1750 4050)(2175 4050);
WIRE 16 -1 (1750 3050)(2175 3050);
WIRE 16 -1 (1750 3100)(2175 3100);
WIRE 16 -1 (1750 3150)(2175 3150);
WIRE 16 -1 (1750 3200)(2175 3200);
WIRE 16 -1 (1750 3250)(2175 3250);
WIRE 16 -1 (1750 3300)(2175 3300);
WIRE 16 -1 (1750 3350)(2175 3350);
WIRE 16 -1 (1750 3400)(2175 3400);
WIRE 16 -1 (1750 3450)(2175 3450);
WIRE 16 -1 (1750 3500)(2175 3500);
WIRE 16 -1 (1750 600)(2175 600);
WIRE 16 -1 (1750 650)(2175 650);
WIRE 16 -1 (1750 700)(2175 700);
WIRE 16 -1 (1750 750)(2175 750);
WIRE 16 -1 (1750 1450)(2175 1450);
WIRE 16 -1 (1750 1500)(2175 1500);
WIRE 16 -1 (1750 1550)(2175 1550);
WIRE 16 -1 (1750 1600)(2175 1600);
WIRE 16 -1 (1750 1650)(2175 1650);
WIRE 16 -1 (1750 1700)(2175 1700);
WIRE 16 -1 (1750 1750)(2175 1750);
WIRE 16 -1 (3275 -50)(1750 -50);
FORCEPROP 2 LAST SIG_NAME M_G_CPU1_SB_RSP<0>
J 0
(2384 -41);
DISPLAY 0.680851 (2384 -41);
PAINT WHITE (2384 -41);
WIRE 16 -1 (3275 0)(1750 0);
FORCEPROP 2 LAST SIG_NAME M_G_CPU1_SB_RSP<1>
J 0
(2384 9);
DISPLAY 0.680851 (2384 9);
PAINT WHITE (2384 9);
WIRE 16 -1 (3275 100)(1750 100);
FORCEPROP 2 LAST SIG_NAME M_G_CPU1_SA_RSP<0>
J 0
(2384 109);
DISPLAY 0.680851 (2384 109);
PAINT WHITE (2384 109);
WIRE 16 -1 (3275 150)(1750 150);
FORCEPROP 2 LAST SIG_NAME M_G_CPU1_SA_RSP<1>
J 0
(2384 159);
DISPLAY 0.680851 (2384 159);
PAINT WHITE (2384 159);
WIRE 16 -1 (3275 -150)(1750 -150);
FORCEPROP 2 LAST SIG_NAME M_G_CPU1_ALERT_N
J 0
(2384 -141);
DISPLAY 0.680851 (2384 -141);
PAINT WHITE (2384 -141);
QUIT
